# B81.00X10.0058_BOM.xlsx — B81.00X10.0058 (bom)
| Level | Parent Number | Part Number | Description | Green Factor | Life Cycle State | Manufacturer | Manufacturer Part Number | Source | BOM Usage | M/P Code | S/D | Qty | UoM | Location |
| 1 | B81.00X10.0058 | B55.00X01.D033 | TP SS 1 MB DDR4 LBGT TE-INF BT - (D) 1B | N/A; | Released |  |  |  | E | Manufacture |  | 1 | PCS |  |
| 2 | B55.00X01.D033 | 006.02907.001A | XTOR PNP 2SB2907A_B0_00001 TO-92 AMMO | R2_SA;HF_SA; | Released | PANJIT | 2SB2907A_B0_00001 | Single |  | Purchase | DIP | 2 | PCS | Q1E1 Q9B1 |
| 2 | B55.00X01.D033 | 022.70001.0441 | BOLSTER SKX EP FOR GAP-AZIF0090-P001C01 | R2_SA;HF_SA; | Released | LOTES | GAP-AZIF0090-P001C01 | Single |  | Purchase | DIP | 1 | PCS |  |
| 2 | B55.00X01.D033 | 022.70001.0451 | BACK PLATE ASSEMBLY AHSK0013-P001C ENG | R2_SA;HF_SA; | Released | LOTES | AHSK0013-P001C | Single |  | Purchase | DIP | 2 | PCS |  |
| 2 | B55.00X01.D033 | 022.70025.0001 | ILM PLATE+COVER FOR CPU AZIF0088-P001C01 | R2_SA;HF_SA; | Obsoleted | LOTES | AZIF0088-P001C01 | Single |  | Purchase | DIP | 1 | PCS |  |
| 2 | B55.00X01.D033 | 025.60010.0001 | JUMPER 2P 200-H71-BBGB50,PBT | R2_SA;HF_SA; | Released | PINREX | 200-H71-BBGB50 | Single |  | Purchase | DIP | 12 | PCS |  |
| 2 | B55.00X01.D033 | 025.60012.0011 | JUMPER MINI 2P CS01502A100-NH BLACK | R2_SA;HF_SA; | Released | CVILUX | CS01502A100-NH | Single |  | Purchase | DIP | 2 | PCS |  |
| 2 | B55.00X01.D033 | 072.25256.0B01 | IC FLASH MEMORY W25Q256FVFIQ SOIC 16P MP | R2_SA;HF_SA; | Obsoleted | WINBOND | W25Q256FVFIQ | Single |  | Purchase | DIP | 1 | PCS | U7F1 |
| 2 | B55.00X01.D033 | 086.1A564.05R0 | SCRW USB_SCREW M3L5(NYLOK) | R2_C;HF_C; | Released | TBD |  | Single |  | Purchase | DIP | 1 | PCS |  |
| 2 | B55.00X01.D033 | 20.81926.072 | CONN CTR PRESS FIT 72P 170729-0002 | R2_SA;HF_SA; | Released | MOLEX | 170729-0002 | Single |  | Purchase | DIP | 1 | PCS | J8A1 |
| 2 | B55.00X01.D033 | 20.82092.076 | CONN CTR 48S+28G 10124755-111LF PRESSFIT | R2_SA;HF_SA; | Released | FCI | 10124755-111LF | Single |  | Purchase | DIP | 2 | PCS | J1C1 J1F1 |
| 2 | B55.00X01.D033 | 20.82093.012 | CONN CTR 12P 10124648-001LF PRESSFIT | R2_SA; | Released | FCI | 10124648-001LF | Single |  | Purchase | DIP | 1 | PCS | J1E1 |
| 2 | B55.00X01.D033 | 20.90080.001 | CONN GUIDE PIN 10045588-101LF | R2_SA;HF_SA; | Released | FCI | 10045588-101LF | Single |  | Purchase | DIP | 1 | PCS | RM1E1 |
| 2 | B55.00X01.D033 | 23.20068.001 | BTY RTC CR2032 KTS | R2_SA;HF_SA; | Released | KTS | BBBCR2032BX | Single |  | Purchase | DIP | 1 | PCS | BT8G1 |
| 2 | B55.00X01.D033 | 40.54T02.001 | LBL BIOS 70*50 P97AE | R2_SA; | Released | CHENG MAY |  | Single |  | Purchase | DIP | 2 | PCS |  |
| 2 | B55.00X01.D033 | 40.63M04.001 | LBL 7*6 FOR IC LABEL | R2_SA;HF_SA; | Released | BRADY;LABELJET | 40.63M04.001 | Multiple |  | Purchase | DIP | 3 | PCS |  |
| 2 | B55.00X01.D033 | 40.6F301.001 | LBL POLYMIDE B478 28*5MM | R2_SA;HF_SA; | Released | BRADY | 40.6F301.001 | Single |  | Purchase | DIP | 3 | PCS |  |
| 2 | B55.00X01.D033 | 42.5N207.001 | SPACER PCB NYLON 66 WINDMILL | R2_SA;HF_SA; | Released | TBD |  | Single |  | Purchase | DIP | 2 | PCS |  |
| 2 | B55.00X01.D033 | 72.25256.H01 | IC FEROM W25Q256FVFIG SOIC 16P | R2_SA;HF_SA; | Obsoleted | WINBOND | W25Q256FVFIG | Single |  | Purchase | DIP | 2 | PCS | U8F2 UN8F2 |
| 2 | B55.00X01.D033 | B34.00X01.0001 | LATCH MEZZ H5MM LEFT NYLON | R2_SA;HF_SA; | Released | TBD |  | Single |  | Purchase | DIP | 1 | PCS |  |
| 2 | B55.00X01.D033 | B34.00X02.0001 | LATCH MEZZ H5MM RIGHT NYLON | R2_SA;HF_SA; | Released | TBD |  | Single |  | Purchase | DIP | 3 | PCS |  |
| 2 | B55.00X01.D033 | B40.00X08.0001 | LBL 10.5*5.7MM BMC SECURE FOR TIOGA PASS | R2_SA;HF_SA; | Released | TBD |  | Single |  | Purchase | DIP | 1 | PCS |  |
| 2 | B55.00X01.D033 | B40.00X08.0011 | LBL 10.5*5.7MM BMC FW FLASH TIOGA PASS | R2_SA;HF_SA; | Released | TBD |  | Single |  | Purchase | DIP | 1 | PCS |  |
| 2 | B55.00X01.D033 | B40.00X08.0021 | LBL 10.5*5.7MM BIOS FLASH TIOGA PASS | R2_SA;HF_SA; | Released | TBD |  | Single |  | Purchase | DIP | 1 | PCS |  |
| 2 | B55.00X01.D033 | B42.00X0B.0001 | TIOGA PASS M.2 SLIDING LACTH H5 | R2_SA;HF_SA; | Released | FIVETECH | TBD | Single |  | Purchase | DIP | 1 | PCS |  |
| 2 | B55.00X01.D033 | B47.00X0E.0001 | RUB MB BUMPER H2.5 TP SS | R2_SA;HF_SA; | Released | TBD |  | Single |  | Purchase | DIP | 8 | PCS |  |
| 2 | B55.00X01.D033 | B50.00X0G.0001 | C.A. TE LONG TERM PRESFIT ADD FUSE | Regular; | Released | TE | TE | Single |  | Purchase | DIP | 1 | PCS | J1D1 |
| 2 | B55.00X01.D033 | B55.00X01.S033 | TP SS 1 MB DDR4 LBGT TE-INF BT - (S) 1B | N/A; | Released |  |  |  | E | Manufacture | DIP | 1 | PCS |  |
| 3 | B55.00X01.S033 | 020.80491.0014 | CONN CTR 14P ASP-165694-02 | R2_SA;HF_SA; | Released | SAMTEC | ASP-165694-02 | Single |  | Purchase | SMT | 1 | PCS | J9A2 |
| 3 | B55.00X01.S033 | 020.C0066.0200 | CONN EDGE CARD 200P REF-184468-01 SMD | R2_SA;HF_SA; | Released | SAMTEC | REF-184468-01 | Single |  | Purchase | SMT | 1 | PCS | J8G1 |
| 3 | B55.00X01.S033 | 020.C0082.0060 | CONN 60P HSEC8-130-01-S-DV-A-WT-K-TR | R2_SA;HF_SA; | Released | SAMTEC | HSEC8-130-01-S-DV-A-WT-K-TR | Single |  | Purchase | SMT | 1 | PCS | CONX8 |
| 3 | B55.00X01.S033 | 020.F0209.0080 | CONN CTR 80P 61082-081402LF SMD ,LCP | R2_SA;HF_SA; | Released | FCI | 61082-081402LF | Single |  | Purchase | SMT | 1 | PCS | J8E3 |
| 3 | B55.00X01.S033 | 020.F0293.0024 | CONN CTR WTB 24P SMD 50238-0247C-001,LCP | R2_SA;HF_SA; | Released | ACES | 50238-0247C-001 | Single |  | Purchase | SMT | 1 | PCS | J8B1 |
| 3 | B55.00X01.S033 | 020.F0528.0011 | CONN CTR 11P 91931-31111LF SMD | R2_SA;HF_SA; | Released | FCI | 91931-31111LF | Single |  | Purchase | SMT | 1 | PCS | J8E1 |
| 3 | B55.00X01.S033 | 020.F0626.0120 | CONN CTR 120P REF-187531-02 SMD | R2_SA;HF_SA; | Released | SAMTEC | REF-187531-02 | Single |  | Purchase | SMT | 4 | PCS | J4B2 J4E1 J6B1 J6E1 |
| 3 | B55.00X01.S033 | 021.60469.0206 | HEAD ML 2R12P HBC1061-L200D-9H | R2_SA;HF_SA; | Released | FOXCONN | HBC1061-L200D-9H | Single |  | Purchase | SMT | 3 | PCS | J7G3 J8G2 J9G1 |
| 3 | B55.00X01.S033 | 021.60487.0108 | HEAD ML 1R8P 210-HP1-08GBE1 | R2_SA;HF_SA; | Released | PINREX | 210-HP1-08GBE1 | Single |  | Purchase | SMT | 1 | PCS | J7G2 |
| 3 | B55.00X01.S033 | 021.60545.0103 | HEAD ML 1R3P 210-HP1-03GBEF | R2_SA;HF_SA; | Released | PINREX | 210-HP1-03GBEF | Single |  | Purchase | SMT | 3 | PCS | J8C1 J8D4 J9B2 |
| 3 | B55.00X01.S033 | 021.60626.0104 | HEAD ML 1R4P ST APHD0020-P001A | R2_SA;HF_SA; | Released | LOTES | APHD0020-P001A | Single |  | Purchase | SMT | 2 | PCS | J10W1 J1F2 |
| 3 | B55.00X01.S033 | 021.60627.0106 | HEAD ML FAN 1R6P APHD0019-P001A | R2_SA;HF_SA; | Released | LOTES | APHD0019-P001A | Single |  | Purchase | SMT | 1 | PCS | J1B2 |
| 3 | B55.00X01.S033 | 021.D0139.0103 | HEAD ML 1R3P CH11032M100-0P-NH SMD | R2_SA;HF_SA; | Released | CVILUX | CH11032M100-0P-NH | Single |  | Purchase | SMT | 1 | PCS | J1B4 |
| 3 | B55.00X01.S033 | 021.D0181.0113 | HEAD ML 13P T1M-13-GF-S-RA-TR SMD | R2_SA;HF_SA; | Released | SAMTEC | T1M-13-GF-S-RA-TR | Single |  | Purchase | SMT | 1 | PCS | J25W1 |
| 3 | B55.00X01.S033 | 022.10005.05Q1 | SKT USB3.0 A TYPE 4P AUSB0043-P007A | R2_SA;HF_SA; | Released | LOTES | AUSB0043-P007A | Single |  | Purchase | SMT | 1 | PCS | J9B1 |
| 3 | B55.00X01.S033 | 022.10014.0121 | SKT SATA 7+6P ST C18625-11331-L MT DIP | R2_SA;HF_SA; | Released | ALLTOP | C18625-11331-L | Single |  | Purchase | SMT | 1 | PCS | J2W2 |
| 3 | B55.00X01.S033 | 022.70020.0011 | HOLDER BTY CR2032 BB3320E-B1LH | R2_SA;HF_SA; | Released | FOXCONN | BB3320E-B1LH | Single |  | Purchase | SMT | 1 | PCS | XBT8G1 |
| 3 | B55.00X01.S033 | 062.10003.0B21 | SKT NGFF 67P AS0BC23-S67BM-LH SMD | R2_SA;HF_SA; | Released | FOXCONN | AS0BC23-S67BM-LH | Single |  | Purchase | SMT | 1 | PCS | J8F1 |
| 3 | B55.00X01.S033 | 062.10009.0621 | SKT USB 32P UT12113-11601-7H SMD | R2_SA;HF_SA; | Released | FOXCONN | UT12113-11601-7H | Single |  | Purchase | SMT | 1 | PCS | J30W1 |
| 3 | B55.00X01.S033 | 062.10011.0F11 | SKT DIMM DDR4 288P 9-2199155-5 SMD | R2_SA;HF_SA; | Released | TE | 9-2199155-5 | Single |  | Purchase | SMT | 12 | PCS | J1A1 J1A2 J1B1 J1G1 J1G2 J1G3 J4A1 J4A2 J4B1 J4G1 J4G2 J4G3 |
| 3 | B55.00X01.S033 | 062.10015.0421 | SKT LGA3647-P0 LEFT 2-2129710-5 BLACK | R2_SA;HF_SA; | Released | TE | 2-2129710-5 | Single |  | Purchase | SMT | 2 | PCS | XLU1 XLU2 |
| 3 | B55.00X01.S033 | 062.10015.0431 | SKT LGA3647-P0 RIGHT 2-2129710-6 YELLOW | R2_SA;HF_SA; | Released | TE | 2-2129710-6 | Single |  | Purchase | SMT | 2 | PCS | XRU1 XRU2 |
| 3 | B55.00X01.S033 | 062.10029.0051 | SKT SPI CONN 16P ACA-SPI-006-P06 SMD | R2_SA;HF_SA; | Released | LOTES | ACA-SPI-006-P06 | Single |  | Purchase | SMT | 3 | PCS | U7F1 U8F2 UN8F2 |
| 3 | B55.00X01.S033 | 062.40001.0921 | SW TACT 4P DTSJ-65K-S-Q-T/R(984) SMD | R2_SA;HF_SA; | Released | DIPTRONICS | DTSJ-65K-S-Q-T/R(984) | Single |  | Purchase | SMT | 1 | PCS | S9A1 |
| 3 | B55.00X01.S033 | 062.40001.0931 | SW TACT 4P DTSJ-65R-S-Q-T/R(984) SMD | R2_SA;HF_SA; | Released | DIPTRONICS | DTSJ-65R-S-Q-T/R(984) | Single |  | Purchase | SMT | 1 | PCS | S9A2 |
| 3 | B55.00X01.S033 | 062.40005.0011 | SW PUSH BUTTOM TL1015AF160QG NATURALPA46 | R2_SA;HF_SA; | Released | ESWITCH | TL1015AF160QG | Single |  | Purchase | SMT | 1 | PCS | S8E1 |
| 3 | B55.00X01.S033 | 064.1003F.M001 | CHIP RES 100K B 1/8W AT0805 50PPM(FIONA) | R2_SA;HF_SA; | Released | YAGEO | AT0805BRE07100KL | Single |  | Purchase | SMT | 8 | PCS | R12W1 R12W11 R12W12 R12W16 R12W17 R12W2 R12W6 R12W7 |
| 3 | B55.00X01.S033 | 064.2003D.0551 | CHIP RES 200K B 1/10W 0603 MP | R2_SA;HF_SA;G_SA; | Released | YAGEO;TAI;RALEC;WALSIN | RT0603BRE07200KL;RM06BTN2003;RTT032003BTP;WF06Q2003BTL | Multiple |  | Purchase | SMT | 1 | PCS | R7C1 |
| 3 | B55.00X01.S033 | 064.2490D.06D1 | CHIP RES 249R B 1/16W 0402 | R2_SA;HF_SA;G_SA; | Released | YAGEO;TAI;RALEC;WALSIN | RE0402BRE07249RL;RM04BTN2490;RTT022490BTH;WF04H2490BTL | Multiple |  | Purchase | SMT | 2 | PCS | R3D27 R5D5 |
| 3 | B55.00X01.S033 | 064.7501D.06DD | CHIP RES 7.5K B 1/16W 0402 | R2_SA;HF_SA;G_SA; | Released | WALSIN;YAGEO;KOA;SEI | WF04T7501BTL;RT0402BRE077K5L;RN731ETTP7501B50;RNCF0402BTC7K50 | Multiple |  | Purchase | SMT | 1 | PCS | R1D43 |
| 3 | B55.00X01.S033 | 064.R0015.0C71 | CHIP RES 0.001 F 3W 2512 | R2_SA;HF_SA; | Released | TAI;RALEC;YAGEO | RLP25FEGR001;LR2512-23R001F4;PA2512FKF7T0R001E | Multiple |  | Purchase | SMT | 2 | PCS | R1D49 R9R1 |
| 3 | B55.00X01.S033 | 064.R0045.0711 | CHIP RES 0.004 F 1W 1206 | R2_SA;HF_SA; | Released | TAI;RALEC;WALSIN | RLM12FTCMR004;LR1206-21R004F4;WW12RR004FTL | Multiple |  | Purchase | SMT | 4 | PCS | R1F3 R4B12 R4F2 R9M4 |
| 3 | B55.00X01.S033 | 068.00007.0011 | CHIP BEAD BLM31SN500SN1L | R2_SA;HF_SA; | Released | MURATA | BLM31SN500SN1L | Single |  | Purchase | SMT | 1 | PCS | FB9E1 |
| 3 | B55.00X01.S033 | 068.00039.0011 | CHIP BEAD 22N K MLH2012F22NKT | R2_SA;HF_SA; | Released | TDK | MLH2012F22NKT | Single |  | Purchase | SMT | 1 | PCS | L2M1 |
| 3 | B55.00X01.S033 | 068.00085.0011 | CHIP CMMI FILTER CUWI21T-900Y-NWN | R2_SA;HF_SA; | Released | CHILISIN | CUWI21T-900Y-NWN | Single |  | Purchase | SMT | 1 | PCS | L1M2 |
| 3 | B55.00X01.S033 | 068.1011N.M001 | CHIP IND 100NH M HCBS404045-101(FIONA) | R2_SA;HF_SA; | Released | DELTA | HCBS404045-101 | Single |  | Purchase | SMT | 5 | PCS | L1B1 L1F1 L7A5 L7C1 L7F2 |
| 3 | B55.00X01.S033 | 068.1202N.M001 | CHIP IND 120NH K HCUVE966490D-121(FIONA) | R2_SA;HF_SA; | Released | DELTA | HCUVE966490D-121 | Single |  | Purchase | SMT | 14 | PCS | L1A2 L1C2 L1D1 L1D2 L1D3 L1E1 L1G1 L4C3 L4D1 L4D2 L4D3 L4E1 L7A1 L7G1 |
| 3 | B55.00X01.S033 | 068.1512N.M001 | CHIP IND 150NH K HCUVE966490D-151(FIONA) | R2_SA;HF_SA; | Released | DELTA | HCUVE966490D-151 | Single |  | Purchase | SMT | 2 | PCS | L4E2 L7C2 |
| 3 | B55.00X01.S033 | 068.1R010.1781 | CHIP IND 1.0UH M MHD-07EZP1R0M-XCW SMD | R2_SA;HF_SA; | Released | MAGLAYER | MHD-07EZP1R0M-XCW | Single |  | Purchase | SMT | 1 | PCS | L8F1 |
| 3 | B55.00X01.S033 | 068.2R210.1641 | CHIP IND 2.2UH M SM2511-2R2MHF | R2_SA;HF_SA; | Released | ITG | SM2511-2R2MHF | Single |  | Purchase | SMT | 1 | PCS | L8E1 |
| 3 | B55.00X01.S033 | 068.3012N.1001 | CHIP IND 300NH K SL3732H-R30KHF | R2_SA;HF_SA; | Released | ITG | SL3732H-R30KHF | Single |  | Purchase | SMT | 2 | PCS | L7A2 L7A4 |
| 3 | B55.00X01.S033 | 068.3012N.1011 | CHIP IND 300NH K SL3732A-R30KHF | R2_SA;HF_SA; | Released | ITG | SL3732A-R30KHF | Single |  | Purchase | SMT | 2 | PCS | L1C1 L4C2 |
| 3 | B55.00X01.S033 | 068.8001N.M001 | CHIP IND 80NH M HCBS5265-800 SMD(FIONA) | R2_SA;HF_SA; | Released | DELTA | HCBS5265-800 | Single |  | Purchase | SMT | 2 | PCS | L1B2 L4C1 |
| 3 | B55.00X01.S033 | 068.R4710.1011 | CHIP IND 0.47UH M MMD-06CZ-R47M-V1-IN | R2_SA;HF_SA; | Released | MAGLAYERS | MMD-06CZ-R47M-V1-IN | Single |  | Purchase | SMT | 4 | PCS | L4A1 L4G1 L7B1 L7F1 |
| 3 | B55.00X01.S033 | 069.50007.0071 | POLYSW 1.75A 8V LP-ISML175 0805 SMD | R2_SA;HF_SA; | Released | CYGWAYON | LP-ISML175 | Single |  | Purchase | SMT | 1 | PCS | F25W1 |
| 3 | B55.00X01.S033 | 069.50018.0001 | POLYSW 0.50A 8V LP-TSML050/8 0603 SMD | R2_SA;HF_SA; | Released | CYGWAYON | LP-TSML050/8 | Single |  | Purchase | SMT | 1 | PCS | F1L1 |
| 3 | B55.00X01.S033 | 071.02014.000W | IC XALTOR SN74GTL2014PWR TSSOP 14P | R2_SA;HF_SA; | Released | TI | SN74GTL2014PWR | Single |  | Purchase | SMT | 8 | PCS | U25W10 U25W11 U2T4 U3P1 U3P2 U4C2 U7D2 U9G1 |
| 3 | B55.00X01.S033 | 071.02500.0B0U | IC VGA AST2500A2-GP 19X19 TFBGA 456P | R2_SA;HF_SA; | Released | ASPEED | AST2500A2-GP | Single |  | Purchase | SMT | 1 | PCS | U25W4 |
| 3 | B55.00X01.S033 | 071.09204.0A03 | IC CLK 9FGP204BKLF MLF 40P | R2_SA;HF_SA; | Released | IDT | 9FGP204BKLF | Single |  | Purchase | SMT | 1 | PCS | EU8F2 |
| 3 | B55.00X01.S033 | 071.09517.0009 | IC REPEATER TCA9517DGKR MSOP 8P | R2_SA;HF_SA; | Released | TI | TCA9517DGKR | Single |  | Purchase | SMT | 5 | PCS | U1B2 U1W2 U32W1 U32W2 U6W2 |
| 3 | B55.00X01.S033 | 071.09555.000W | IC I/O EXPANDER TCA9555PWR TSSOP 24P | R2_SA;HF_SA; | Released | TI | TCA9555PWR | Single |  | Purchase | SMT | 1 | PCS | U6W1 |
| 3 | B55.00X01.S033 | 071.31200.0003 | IC BUFFER NB3W1200LMNTXG QFN 64P | R2_SA;HF_SA; | Released | ON | NB3W1200LMNTXG | Single |  | Purchase | SMT | 1 | PCS | EU4D2 |
| 3 | B55.00X01.S033 | 072.40256.0A0U | IC SDRAM DDR4-2400 256M*16 MT40A256M16GE | R2_SA;HF_SA; | Released | MICRON | MT40A256M16GE-083E:B | Single |  | Purchase | SMT | 1 | PCS | U25W5 |
| 3 | B55.00X01.S033 | 073.02400.0E0U | IC CPLD LCMXO2-4000HC-4BG256C2U BGA 256P | R2_SA;HF_SA; | Released | LATTICE | LCMXO2-4000HC-4BG256C2U | Single |  | Purchase | SMT | 1 | PCS | U8D7 |
| 3 | B55.00X01.S033 | 073.03126.0003 | IC FET BUS SW N74CBTLV3126RGYR RGY 14P | R2_SA;HF_SA; | Released | TI | SN74CBTLV3126RGYR | Single |  | Purchase | SMT | 5 | PCS | U1L1 U1L10 U1L5 U25W12 U25W16 |
| 3 | B55.00X01.S033 | 073.04564.000G | IC ANALOG SWITCH MAX4564EKA+ SOT23 8PIN | R2_SA;HF_SA; | Released | MAXIM | MAX4564EKA+ | Single |  | Purchase | SMT | 1 | PCS | U25W13 |
| 3 | B55.00X01.S033 | 073.53157.000J | IC SPDT CMOS SW PI5A3157BC6E SC70 6P | R2_SA;HF_SA; | Released | PERICOM | PI5A3157BC6E | Single |  | Purchase | SMT | 1 | PCS | U7W1 |
| 3 | B55.00X01.S033 | 073.7PZ14.0007 | IC CMOS TC7PZ14FU SSOP6 | R2_SA;HF_SA; | Released | TOSHIBA | TC7PZ14FU | Single |  | Purchase | SMT | 3 | PCS | U2R1 U9A3 U9A4 |
| 3 | B55.00X01.S033 | 074.01110.M001 | IC CONT PXE1110CDM-G003 QFN 40P (FIONA) | R2_SA;HF_SA; | Released | INFINEON | PXE1110CDM-G003 | Single |  | Purchase | SMT | 3 | PCS | EU3P1 EU4D5 EU8A1 |
| 3 | B55.00X01.S033 | 074.01310.M007 | IC PWM CTRL PXM1310CDM-G003 QFN 40P((FB) | R2_SA;HF_SA; | Released | INFINEON | PXM1310CDM-G003 | Single |  | Purchase | SMT | 4 | PCS | EU1B1 EU1G2 EU7A5 EU7G1 |
| 3 | B55.00X01.S033 | 074.01610.M005 | IC CONT PXE1610CDN-G003 QFN 48P(FIONA) | R2_SA;HF_SA; | Released | INFINEON | PXE1610CDN-G003 | Single |  | Purchase | SMT | 2 | PCS | EU1C2 EU4D4 |
| 3 | B55.00X01.S033 | 074.02061.007F | IC PWR SW TPS2061DBVR SOT023 5P | R2_SA;HF_SA; | Released | TI | TPS2061DBVR | Single |  | Purchase | SMT | 1 | PCS | U1M3 |
| 3 | B55.00X01.S033 | 074.03232.0A73 | IC H.C. SYN CONV NCP3232LMNTXG QFN-40P | R2_SA;HF_SA; | Released | ON | NCP3232LMNTXG | Single |  | Purchase | SMT | 4 | PCS | EU4A3 EU4G1 EU7B1 EU7F1 |
| 3 | B55.00X01.S033 | 074.03700.0023 | IC V.C TPS3700DSER WSON 6P | R2_SA;HF_SA; | Released | TI | TPS3700DSER | Single |  | Purchase | SMT | 4 | PCS | U1D2 U8D8 U9P1 U9P2 |
| 3 | B55.00X01.S033 | 074.05166.0033 | IC 3A H.S. LV DDR MIC5166YML TR MLF 10P | R2_C;HF_C; | Released | MICREL | MIC5166YML TR | Single |  | Purchase | SMT | 4 | PCS | EU4A1 EU4A2 EU4G2 EU4G3 |
| 3 | B55.00X01.S033 | 074.09059.0033 | IC V.R RT9059GQW WDFN-10L | R2_SA;HF_SA; | Released | RICHTEK | RT9059GQW | Single |  | Purchase | SMT | 4 | PCS | EU25F2 EU8A2 EU9F1 EU9F2 |
| 3 | B55.00X01.S033 | 074.21460.M001 | IC CONVERTER TDA21460 PQFN 41P R13B(FB) | R2_SA;HF_SA; | Released | INFINEON | TDA21460 | Single |  | Purchase | SMT | 6 | PCS | EU1C1 EU4C1 EU4E2 EU7A2 EU7A3 EU7C1 |
| 3 | B55.00X01.S033 | 074.21470.M002 | IC CONVERTER TDA21470 PQFN 41P (FIONA) | R2_SA;HF_SA; | Released | INFINEON | TDA21470 | Single |  | Purchase | SMT | 14 | PCS | EU1A2 EU1C3 EU1D1 EU1D3 EU1D4 EU1E2 EU1G1 EU4C2 EU4D1 EU4D3 EU4D6 EU4E1 EU7A1 EU7G2 |
| 3 | B55.00X01.S033 | 074.8240C.0073 | IC H.E. PWM CONT RT8240CZQW WQFN 12P | R2_SA;HF_SA; | Released | RICHTEK | RT8240CZQW | Single |  | Purchase | SMT | 1 | PCS | EU8F1 |
| 3 | B55.00X01.S033 | 075.06333.007C | IC MOSFET FDC6333C SUPERSOT-6 PIN | R2_SA;HF_SA; | Released | FAIRCHILD | FDC6333C | Single |  | Purchase | SMT | 4 | PCS | Q12W1 Q12W2 Q12W3 Q12W4 |
| 3 | B55.00X01.S033 | 075.063D1.007C | IC FETMOS DMN63D1LDW-7 NC SOT-363 ESD 2K | R2_SA;HF_SA; | Released | DIODES | DMN63D1LDW-7 | Single |  | Purchase | SMT | 7 | PCS | Q1D1 Q1L4 Q1W2 Q1W4 Q25W4 Q4W1 Q9P1 |
| 3 | B55.00X01.S033 | 075.87384.007G | IC FET MOS CSD87384M PATB 5P | R2_SA;HF_SA; | Obsoleted | TI | CSD87384M | Single |  | Purchase | SMT | 1 | PCS | EU8E1 |
| 3 | B55.00X01.S033 | 077.51081.0011 | CHIP CAP EL POLAR 100U 16V M 5*5.8 | R2_SA;HF_SA; | Released | CHEMICON | APXG160ARA101ME61G | Single |  | Purchase | SMT | 1 | PCS | C7W2 |
| 3 | B55.00X01.S033 | 077.56861.0001 | CHIP CAP EL 68U 16V M7343 ESR40 | R2_SA;HF_SA; | Released | PANASONIC | EEFCX1C680R | Single |  | Purchase | SMT | 16 | PCS | C1M5 C1R23 C3B6 C3T13 C3T15 C3T3 C3T6 C4B14 C4F4 C4F5 C4M6 C4M7 C6N5 C7M6 C9M3 C9T3 |
| 3 | B55.00X01.S033 | 077.C3361.0001 | CHIP CAP POLY T 33U 16V M3528 ESR70 | R2_SA;HF_SA; | Released | NECTOKIN | TEPSLB21C336M8R | Single |  | Purchase | SMT | 3 | PCS | C1G12 C1G15 C1G7 |
| 3 | B55.00X01.S033 | 077.C3371.0041 | CHIP CAP POLY T 330U 10V M 7343 10TPE330 | R2_SA;HF_SA; | Released | PANASONIC | 10TPE330M | Single |  | Purchase | SMT | 1 | PCS | C9B8 |
| 3 | B55.00X01.S033 | 077.C4771.0061 | CHIP CAP POLY T 470U 6.3V M 6TPE470MAZU | R2_SA;HF_SA; | Released | PANASONIC | 6TPE470MAZU | Single |  | Purchase | SMT | 2 | PCS | C8F14 C8F8 |
| 3 | B55.00X01.S033 | 078.10520.02F1 | CHIP CAP C 1UF 6.3V K0402 X7R | R2_SA;HF_SA;G_SA; | Released | MURATA;DARFON;YAGEO | GRM155R70J105KA12D;C1005X7R105KCT;CC0402KRX7R5BB105 | Multiple |  | Purchase | SMT | 112 | PCS | C1B3 C1B6 C1C13 C1C7 C1G23 C1G27 C1L10 C1L18 C1L5 C1M21 C1M25 C1M3 C1M32 C1M37 C1T21 C25W12 C25W91 C2L8 C2M16 C2M18 C2M19 C2M20 C2M21 C2M22 C2M25 C2M6 C2M7 C2M8 C2M9 C2N11 C2N12 C2N13 C2N15 C2N16 C2N18 C2N19 C2N2 C2N20 C2N25 C2N26 C2N3 C2N4 C2N5 C2N7 C2N8 C2N9 C2R12 C2T19 C2T28 C2T31 C2T33 C2T38 C2U26 C3C1 C3C2 C3M19 C3M20 C3M21 C3M22 C3M27 C3M29 C3M30 C3M31 C3M38 C3M39 C3M42 C3M43 C3M46 C3N1 C3N15 C3N16 C3N17 C3N18 C3N19 C3N2 C3N20 C3N21 C3N22 C3N23 C3N25 C3N3 C3N32 C3N4 C3N40 C3N5 C3N6 C3N7 C3P3 C3P4 C3P42 C4C3 C4D15 C4D23 C4D25 C4D27 C4D31 C4D36 C4F1 C4F3 C4T1 C4T2 C7A37 C7B1 C7C19 C7F16 C7F18 C7F2 C8A7 C8F4 C8W5 C9A6 CN8F1 |
| 3 | B55.00X01.S033 | 078.10521.08F1 | CHIP CAP C 1UF 16V K 0402 X6S | R2_SA;HF_SA;G_SA; | Released | MURATA;DARFON;YAGEO;TAIYO | GRM155C81C105KE11D;C1005X6S105KET;CC0402KRX6S7BB105;LMK105C6105KV-F | Multiple |  | Purchase | SMT | 101 | PCS | C1A19 C1A9 C1B20 C1C15 C1C26 C1C5 C1D12 C1D17 C1D19 C1D23 C1D25 C1D32 C1D35 C1D7 C1E13 C1E24 C1E8 C1F27 C1G13 C1G6 C1L1 C1L119 C1L19 C1U19 C25W1 C25W2 C25W23 C25W24 C25W25 C25W26 C25W27 C25W28 C25W3 C25W32 C25W33 C25W35 C25W37 C25W4 C25W40 C25W41 C25W42 C25W43 C25W44 C25W48 C25W5 C25W51 C25W52 C25W53 C25W54 C25W56 C25W6 C25W60 C25W66 C25W67 C25W71 C25W92 C25W94 C25W98 C3M9 C3P50 C3T10 C4A10 C4A14 C4A8 C4A9 C4C18 C4C6 C4C9 C4D10 C4D16 C4D30 C4D46 C4D48 C4D7 C4E10 C4E15 C4E19 C4E22 C4E26 C4G15 C4G16 C4G18 C4G21 C4G4 C6L11 C7A10 C7A11 C7A16 C7A21 C7A6 C7A7 C7A9 C7C12 C7C17 C7D4 C7E14 C7G30 C7G33 C7G37 C8E14 C9E11 |
| 3 | B55.00X01.S033 | 078.10610.08B1 | CHIP CAP C 10UF 6.3V M 0603 X6S | R2_SA;HF_SA; | Released | MURATA;SAMSUNG;DARFON;YAGEO;TAIYO | GRM188C80J106MA73D;CL10X106MQ8NNNC;C1608X6S106MCT;CC0603MRX6S5BB106;JMK107BC6106MA-T | Multiple |  | Purchase | SMT | 18 | PCS | C1T15 C1T7 C1W15 C1W7 C2N14 C2N17 C2N21 C2N22 C2N23 C2N24 C7D2 C8A6 C8C3 C8C4 C8C5 C8C6 C9E10 C9F3 |
| 3 | B55.00X01.S033 | 078.1061T.M001 | CHIP CAP C 10U 4V M0603 X6S (FIONA) | R2_SA;HF_SA; | Released | MURATA | GRM188C80G106ME47D | Single |  | Purchase | SMT | 60 | PCS | C2D10 C2D11 C2D8 C2D9 C3A3 C3A4 C3A7 C3A8 C3B1 C3B2 C3F3 C3F4 C3G3 C3G4 C3G7 C3G8 C4L1 C4L2 C4L3 C4L4 C4M3 C4M4 C4M5 C4T5 C4T6 C4U1 C4U2 C4U3 C4U4 C5D10 C5D11 C5D12 C5D13 C5T4 C6A2 C6A3 C6A6 C6A7 C6B1 C6B2 C6F5 C6F6 C6G1 C6G2 C6G4 C6G5 C7L2 C7L3 C7L6 C7L7 C7M3 C7M4 C7T2 C7T3 C7U3 C7U4 C7U5 C7U6 C8M10 C8T4 |
| 3 | B55.00X01.S033 | 078.10621.0211 | CHIP CAP C 10UF 16V K0805 X7R | R2_SA;HF_SA;G_SA; | Released | SAMSUNG;YAGEO | CL21B106KOQNNNE;CC0805KKX7R7BB106 | Multiple |  | Purchase | SMT | 118 | PCS | C10W1 C1A16 C1A4 C1B18 C1B7 C1E21 C1M26 C1M27 C25W46 C2T22 C2U1 C2U2 C3D22 C3L10 C3L11 C3L12 C3L13 C3L15 C3L16 C3L17 C3L2 C3L4 C3L7 C3L8 C3L9 C3M15 C3M16 C3M8 C3N33 C3N34 C3N36 C3T12 C3T14 C3T8 C3U2 C3U3 C3U4 C3U6 C3U7 C3U9 C4A17 C4A19 C4A4 C4B11 C4G2 C6L10 C6M3 C6M5 C6N10 C6N11 C6N2 C6N3 C6N6 C6N8 C6P13 C6P15 C6P17 C6P19 C6P20 C6P22 C6P24 C6P7 C6R10 C6R11 C6R13 C6R14 C6R4 C6R6 C6R8 C6T2 C6U10 C6U18 C6U4 C6U7 C6U8 C7B5 C7E6 C7E8 C7F5 C8B12 C8B6 C9B1 C9B2 C9L10 C9L11 C9L13 C9L14 C9L5 C9L6 C9M10 C9M4 C9N13 C9N19 C9N21 C9N25 C9N26 C9N27 C9P1 C9P2 C9P22 C9P24 C9P25 C9P26 C9P4 C9P7 C9P9 C9R10 C9R11 C9R7 C9T4 C9T6 C9T8 C9T9 C9U11 C9U3 C9U4 C9U6 C9U8 |
| 3 | B55.00X01.S033 | 078.1071T.0811 | CHIP CAP C 100U 4V M0805 X6S MP | R2_SA;HF_SA; | Released | MURATA;DARFON | GRM21BC80G107ME15L;C2012X6S107MBP | Multiple |  | Purchase | SMT | 48 | PCS | C4P2 C4P3 C4P4 C4P5 C4P7 C4W5 C5L4 C5L5 C5P10 C5P11 C5P12 C5P13 C5P18 C5P19 C5P20 C5P21 C5P28 C5P29 C5P30 C5P31 C5U12 C5U16 C6W11 C6W12 C6W13 C7P10 C7P11 C7P13 C7P14 C7P15 C7P4 C7P5 C7P6 C7P7 C7P8 C7P9 C8L3 C8L4 C8P14 C8P15 C8P22 C8P23 C8P8 C8P9 C8T3 C8U10 C8W3 C8W4 |
| 3 | B55.00X01.S033 | 078.22611.0811 | CHIP CAP C 22U 16V M0805 X6S | R2_SA;HF_SA; | Released | MURATA;YAGEO;DARFON | GRM21BC81C226ME44L;CC0805MKX6S7BB226;C2012X6S226MEP | Multiple |  | Purchase | SMT | 67 | PCS | C1G2 C22W1 C22W10 C22W11 C22W12 C22W13 C22W14 C22W15 C22W16 C22W17 C22W18 C22W19 C22W2 C22W20 C22W21 C22W22 C22W23 C22W24 C22W25 C22W26 C22W27 C22W28 C22W29 C22W3 C22W30 C22W31 C22W32 C22W33 C22W4 C22W5 C22W6 C22W7 C22W8 C22W9 C30W3 C30W4 C30W5 C30W6 C30W7 C30W8 C30W9 C4B1 C4E14 C4E8 C4E9 C4G5 C7A13 C7A14 C7B8 C7C7 C7C8 C7E12 C7E13 C7F7 C7W10 C7W11 C7W12 C7W13 C7W5 C7W6 C7W7 C7W8 C7W9 C8E11 C8E7 C8E9 C9F1 |
| 3 | B55.00X01.S033 | 078.2261T.M001 | CHIP CAP 22U 4V M0603 X6S (FIONA) | R2_SA;HF_SA; | Released | MURATA | GRM188C80G226MEA0D | Single |  | Purchase | SMT | 324 | PCS | C1C19 C1D14 C1D24 C1D3 C1E3 C1E9 C2A1 C2A10 C2A11 C2A12 C2A13 C2A14 C2A15 C2A2 C2A3 C2A4 C2A6 C2A7 C2A9 C2D1 C2D12 C2D13 C2D14 C2D15 C2D16 C2D17 C2D19 C2D2 C2D20 C2D21 C2D22 C2D23 C2D24 C2D25 C2D26 C2D27 C2D3 C2D30 C2D31 C2D32 C2D33 C2D34 C2D35 C2D36 C2D37 C2D38 C2D4 C2D41 C2D42 C2D43 C2D44 C2D45 C2D46 C2D47 C2D5 C2D6 C2D7 C2G1 C2G10 C2G11 C2G12 C2G13 C2G14 C2G2 C2G3 C2G4 C2G5 C2G6 C2G9 C3A1 C3A2 C3A5 C3A6 C3D1 C3D15 C3D16 C3D2 C3D23 C3D24 C3D25 C3D8 C3D9 C3E1 C3G1 C3G2 C3G5 C3G6 C4D12 C4D34 C4D4 C4E11 C4E3 C4M2 C4P6 C4P8 C5A1 C5A11 C5A12 C5A13 C5A14 C5A15 C5A16 C5A17 C5A18 C5A19 C5A2 C5A3 C5A4 C5A6 C5A7 C5A8 C5A9 C5D1 C5D14 C5D15 C5D16 C5D17 C5D18 C5D19 C5D2 C5D24 C5D25 C5D26 C5D27 C5D28 C5D29 C5D3 C5D30 C5D31 C5D32 C5D39 C5D4 C5D40 C5D41 C5D42 C5D43 C5D44 C5D45 C5D46 C5D47 C5D5 C5D54 C5D55 C5D56 C5D57 C5D58 C5D59 C5D6 C5D60 C5D61 C5D7 C5D8 C5D9 C5G1 C5G100 C5G101 C5G102 C5G103 C5G104 C5G105 C5G106 C5G107 C5G108 C5G109 C5G11 C5G110 C5G111 C5G112 C5G113 C5G114 C5G12 C5G13 C5G14 C5G15 C5G16 C5G17 C5G18 C5G2 C5G3 C5G4 C5G41 C5G42 C5G43 C5G44 C5G45 C5G46 C5G47 C5G48 C5G49 C5G5 C5G50 C5G51 C5G52 C5G53 C5G54 C5G55 C5G56 C5G57 C5G58 C5G59 C5G6 C5G60 C5G61 C5G62 C5G63 C5G64 C5G65 C5G66 C5G67 C5G68 C5G69 C5G7 C5G70 C5G71 C5G72 C5G73 C5G74 C5G75 C5G76 C5G79 C5G8 C5G80 C5G81 C5G82 C5G83 C5G84 C5G85 C5G86 C5G87 C5G88 C5G89 C5G90 C5G91 C5G92 C5G93 C5G94 C5G95 C5G96 C5G97 C5G98 C5G99 C5L10 C5L11 C5L12 C5L13 C5L6 C5L7 C5L8 C5L9 C5M1 C5M2 C5M4 C5M5 C5M6 C5M7 C5T10 C5T11 C5T12 C5T5 C5T6 C5T7 C5T8 C5T9 C5U2 C5U3 C5U4 C5U5 C5U6 C5U7 C5U8 C5U9 C6D10 C6D3 C6D4 C6D6 C6D7 C6D9 C6P16 C6P21 C6P3 C6R2 C6R7 C7C10 C7C6 C7L4 C7L5 C7M1 C7M2 C7P12 C7P16 C7R1 C7T4 C7T5 C7U1 C7U2 C8L10 C8L5 C8L6 C8L7 C8L8 C8L9 C8M1 C8M3 C8M4 C8M5 C8M6 C8T10 C8T5 C8T6 C8T7 C8T8 C8T9 C8U2 C8U3 C8U4 C8U5 C8U6 C8U7 C9N22 C9P10 C9P20 C9P3 C9R2 C9R8 |
| 3 | B55.00X01.S033 | 078.27321.02F1 | CHIP CAP C 0.027U 16V K0402 X7R | R2_SA;HF_SA;G_SA; | Released | YAGEO;DARFON;MURATA;WALSIN;SAMSUNG | CC0402KRX7R7BB273;C1005X7R273KET;GRM155R71C273KA01D;0402B273K160CT;CL05B273KO5NNNC | Multiple |  | Purchase | SMT | 4 | PCS | C4B6 C4G8 C7B11 C7F10 |
| 3 | B55.00X01.S033 | 078.47520.02B1 | CHIP CAP C 4.7U 6.3V K0603 X7R | R2_SA;HF_SA; | Released | SAMSUNG;TAIYO | CL10B475KQ8NQNC;JMK107BB7475KA-T | Multiple |  | Purchase | SMT | 13 | PCS | C25W19 C25W30 C25W36 C25W39 C25W47 C25W50 C25W62 C25W69 C25W70 C4A11 C4A7 C6U11 C6U12 |
| 3 | B55.00X01.S033 | 078.47521.08BD | CHIP CAP C 4.7UF 16V K0603 X6S | R2_SA;HF_SA; | Released | MURATA;SAMSUNG;WALSIN | GRM188C81C475KE11D;CL10X475KO8NQNC;0603S475K160CT | Multiple |  | Purchase | SMT | 5 | PCS | C2R11 C3M10 C3T11 C6L12 C6U6 |
| 3 | B55.00X01.S033 | 078.4761T.05BD | CHIP CAP C 47U 4V M0603 X5R | R2_SA;HF_SA;G_SA; | Released | MURATA;SAMSUNG;DARFON;TAIYO;YAGEO | GRM188R60G476ME15D;CL10A476MR8NZNE;C1608X5R476MBT;ADK107BBJ476MA-R;CC0603MKX5R4BB476 | Multiple |  | Purchase | SMT | 4 | PCS | C3F1 C3T1 C3T2 C4F2 |
| 3 | B55.00X01.S033 | 078.4761T.M001 | CHIP CAP C 47U 4V M0805 X6S (FIONA) | R2_SA;HF_SA; | Released | MURATA | GRM21BC80G476ME15L | Single |  | Purchase | SMT | 48 | PCS | C3T7 C3T9 C4B2 C4B3 C4P1 C4P10 C4P9 C5P14 C5P15 C5P16 C5P17 C5P22 C5P23 C5P24 C5P25 C5P26 C5P27 C5P32 C5P33 C5P34 C5P35 C5P36 C5P37 C5P40 C6B3 C6U2 C6U3 C7B7 C7P17 C7P18 C7P19 C7P3 C8P10 C8P11 C8P12 C8P13 C8P16 C8P17 C8P18 C8P19 C8P20 C8P21 C8P24 C8P25 C8P26 C8P27 C8P28 C8P29 |
| 3 | B55.00X01.S033 | 078.4761T.M003 | CHIP CAP C 47U 4V M0603 X5R (FIONA) | R2_SA;HF_SA;G_SA; | Released | MURATA | GRM188R60G476ME15D | Single |  | Purchase | SMT | 4 | PCS | C2F2 C5M13 C5T3 C8M12 |
| 3 | B55.00X01.S033 | 078.68314.0221 | CHIP CAP C 0.068UF 50V M1206 X7R | R2_SA;HF_SA;G_SA; | Obsoleted | MURATA;WALSIN | GRM319R71H683MA01D;1206B683M500CT | Multiple |  | Purchase | SMT | 1 | PCS | C1E2 |
| 3 | B55.00X01.S033 | 079.2771D.0011 | CHIP CAP 270UF 16V M 6.3*9.9 SVPG OS-CON | R2_SA;HF_SA; | Released | PANASONIC | 16SVPG270M | Single |  | Purchase | SMT | 8 | PCS | C1B10 C1C1 C1C2 C1E18 C4C12 C4D2 C4E16 C7G2 |
| 3 | B55.00X01.S033 | 079.47712.0021 | CHIP CAP EL 470U 25V M 10*10.2 | R2_SA;HF_SA; | Released | SUNCON | 25CE470LX | Single |  | Purchase | SMT | 4 | PCS | C1B14 C1F7 C4B13 C4F6 |
| 3 | B55.00X01.S033 | 079.4771V.0001 | CHIP CAP EL 470U 2.5V M 7.3*4.3 | R2_SA;HF_SA; | Released | PANASONIC | EEFGX0E471R | Single |  | Purchase | SMT | 47 | PCS | C3L14 C3L6 C3N14 C3N26 C3N35 C3N38 C3R4 C3U1 C3U5 C3U8 C4C1 C4E24 C4E29 C4E7 C4L5 C4R1 C6A5 C6N1 C6N4 C6N9 C6P14 C6P18 C6P23 C6P8 C6R12 C6R16 C6R3 C6R5 C6R9 C7G28 C9L12 C9L2 C9L4 C9L9 C9N11 C9N20 C9N24 C9P18 C9P23 C9P5 C9P8 C9R3 C9R9 C9T5 C9U2 C9U5 C9U9 |
| 3 | B55.00X01.S033 | 082.20004.0201 | OSC 156.250000MHZ 50PPM UX54F62001 SMD | R2_SA;HF_SA; | Released | PERICOM | UX54F62001 | Single |  | Purchase | SMT | 2 | PCS | Y3F1 Y6F1 |
| 3 | B55.00X01.S033 | 082.30003.0301 | XTAL 32.768KHZ 12.5P20PPM SC-32P SMD | R2_SA;HF_SA; | Released | SEIKO | Q-SC32P03220C5AAAF | Single |  | Purchase | SMT | 1 | PCS | Y7C2 |
| 3 | B55.00X01.S033 | 082.30005.0421 | XTAL 25MHZ 20PF 20PPM 3.2*2.5 SMD FL2500 | R2_SA;HF_SA; | Released | PERICOM | FL2500316Z | Single |  | Purchase | SMT | 1 | PCS | Y8C1 |
| 3 | B55.00X01.S033 | 082.30028.0141 | XTAL 48MHZ 10P30PPM E3SB48E00001KE | R2_SA;HF_SA; | Released | HOSONIC | E3SB48E00001KE | Single |  | Purchase | SMT | 1 | PCS | Y7C1 |
| 3 | B55.00X01.S033 | 083.01514.00AD | DIODE TVS 1.5SMCJ14CA SMC | R2_SA;HF_SA; | Released | PANJIT | 1.5SMCJ14CA | Single |  | Purchase | SMT | 1 | PCS | VR1D1 |
| 3 | B55.00X01.S033 | 084.19N03.0037 | FET MOS BSZ019N03LS NC PG-TSDSON-8 | R2_SA;HF_SA; | Released | INFINEON | BSZ019N03LS | Single |  | Purchase | SMT | 4 | PCS | Q1B1 Q7E7 Q8B1 Q8G1 |
| 3 | B55.00X01.S033 | 086.2AT24.04R6 | THUMB SCREW SMT M3X0.5 L4.6 | R2_SA;HF_SA; | Released | FIVETECH | FIVETECH | Single |  | Purchase | SMT | 1 | PCS | RM1G1 |
| 3 | B55.00X01.S033 | 087.71242.0465 | NUT TPM M3*0.5*L6 NI EVT | R2_SA;HF_SA; | Released | TBD |  | Single |  | Purchase | SMT | 1 | PCS | RM8D1 |
| 3 | B55.00X01.S033 | 20.F0441.060 | CONN SMD 60P BSH-030-01-L-D-A-TR ,LCP | R2_SA;HF_SA; | Released | SAMTEC | BSH-030-01-L-D-A-TR | Single |  | Purchase | SMT | 1 | PCS | J9A3 |
| 3 | B55.00X01.S033 | 20.F1354.120 | CONN CTR SMD 120P 61082-121402LF ,LCP | R2_SA;HF_SA; | Released | FCI | 61082-121402LF | Single |  | Purchase | SMT | 1 | PCS | J9B3 |
| 3 | B55.00X01.S033 | 21.D0458.205 | HEAD ML 2R10P ST G823MB10221KEU SMD | R2_SA;HF_SA; | Released | AMPHENOL | G823MB10221KEU | Single |  | Purchase | SMT | 1 | PCS | J9B4 |
| 3 | B55.00X01.S033 | 62.40018.641 | SW SLIDE 3P MSS3-Q-T/R SMD | R2_SA;HF_SA; | Released | DIPTRONICS | MSS3-Q-T/R | Single |  | Purchase | SMT | 1 | PCS | S9W1 |
| 3 | B55.00X01.S033 | 63.33134.1DL | CHIP RES 330 J 1/16W 0402 | R2_SA;HF_SA;G_SA; | Released | TA-I;RALEC;CYNTEC;YAGEO;WALSIN | RM04JTN331 ; RTT02331JTH ; RR0510S-331-JN ; RC0402JR-07330RL;WR04X331JTL | Multiple |  | Purchase | SMT | 4 | PCS | R1L43 R1L44 R1W31 R1W32 |
| 3 | B55.00X01.S033 | 63.33234.1DL | CHIP RES 3.3K J 1/16W 0402 | R2_SA;HF_SA;G_SA; | Released | TA-I;RALEC;CYNTEC;YAGEO;WALSIN | RM04JTN332;RTT02332JTH;RR-0510S-332-JN;RC0402JR-073K3L;WR04X332JTL | Multiple |  | Purchase | SMT | 7 | PCS | R24W1 R24W2 R32W3 R4W3 R4W4 R8B24 R8B26 |
| 3 | B55.00X01.S033 | 63.33334.1DL | CHIP RES 33K J 1/16W 0402 | R2_SA;HF_SA;G_SA; | Released | TA-I;RALEC;CYNTEC;YAGEO;WALSIN | RM04JTN333;RTT02333JTH;RR0510S-333-JN;RC0402JR-0733KL;WR04X333JTL | Multiple |  | Purchase | SMT | 1 | PCS | R4U4 |
| 3 | B55.00X01.S033 | 63.47134.1DL | CHIP RES 470 J 1/16W 0402 | R2_SA;HF_SA;G_SA; | Released | TA-I;RALEC;CYNTEC;YAGEO;WALSIN | RM04JTN471 ; RTT02471JTH ; RR0510S-471-JN ; RC0402JR-07470RL;WR04X471JTL | Multiple |  | Purchase | SMT | 1 | PCS | R1L8 |
| 3 | B55.00X01.S033 | 63.51034.1DL | CHIP RES 51 J 1/16W 0402 | R2_SA;HF_SA;G_SA; | Released | TA-I;RALEC;CYNTEC;YAGEO;WALSIN | RM04JTN510 ; RTT02510JTH ; RR0510S-510-JN ; RC0402JR-0751RL;WR04X510JTL | Multiple |  | Purchase | SMT | 4 | PCS | R1U12 R1U13 R1U14 R2R6 |
| 3 | B55.00X01.S033 | 63.R0031.16L | CHIP RES 0 J 1/8W 0805 | R2_SA;HF_SA;G_SA; | Released | TAI;RALEC;YAGEO;WALSIN | RM10JTN0 ; RTT05000JTP ; RC0805JR-070RL ; WR08X000PTL | Multiple |  | Purchase | SMT | 3 | PCS | R10W5 R1D41 R1W10 |
| 3 | B55.00X01.S033 | 63.R0034.1DL | CHIP RES 0 J 1/16W 0402 | R2_SA;HF_SA;G_SA; | Released | TAI;RALEC;CYNTEC;YAGEO;WALSIN | RM04JTN0;RTT02000JTH;RR0510X-000-XN;RC0402JR-070RL;WR04X000PTL | Multiple |  | Purchase | SMT | 325 | PCS | R12W25 R12W28 R12W31 R12W34 R1B10 R1B11 R1C14 R1C2 R1C3 R1C5 R1C7 R1D2 R1D24 R1D25 R1D3 R1D44 R1D45 R1E6 R1E7 R1F8 R1G10 R1G9 R1L12 R1L6 R1M10 R1M13 R1M15 R1M16 R1M17 R1M18 R1R1 R1R8 R1T36 R1T37 R1U11 R1U53 R1U54 R1U58 R1U59 R1U60 R1U8 R1W12 R1W14 R1W15 R1W16 R1W17 R1W18 R1W19 R1W20 R1W21 R1W22 R1W23 R1W24 R1W27 R1W28 R1W29 R1W33 R1W34 R25W118 R25W141 R25W143 R25W144 R25W145 R25W154 R25W155 R25W181 R25W186 R25W187 R25W59 R25W74 R25W83 R2L14 R2L17 R2N20 R2N21 R2P1 R2P14 R2R12 R2R4 R2T17 R2T2 R2T20 R2T27 R2T32 R2T40 R2T44 R2T60 R2T64 R2T65 R2T66 R2T67 R2T68 R2U14 R2U15 R2U16 R2U17 R2U18 R2U19 R2U20 R2U21 R2U22 R2U23 R2U24 R2U25 R2U26 R2U27 R2U28 R2U29 R2U37 R2U46 R2U47 R2W3 R2W5 R30W1 R30W2 R30W3 R30W4 R32W10 R32W11 R32W12 R3B3 R3B5 R3D18 R3F2 R3F4 R3L1 R3L4 R3L6 R3M1 R3M6 R3N7 R3P1 R3P11 R3P2 R3P22 R3P26 R3P3 R3P34 R3P35 R3P58 R3P59 R3T13 R3U6 R4A2 R4A3 R4A8 R4A9 R4B1 R4B14 R4B3 R4C2 R4C4 R4D26 R4D47 R4D54 R4D56 R4D66 R4D67 R4E16 R4E17 R4G16 R4G23 R4G25 R4G4 R4G8 R4T1 R5W1 R5W2 R6B4 R6B5 R6F7 R6F9 R6L10 R6L11 R6L6 R6L8 R6N11 R6N12 R6N3 R6P10 R6P18 R6P19 R6P41 R6P47 R6R2 R6R5 R6R6 R6U4 R6U5 R6U6 R6U7 R6W17 R6W18 R760 R767 R768 R769 R771 R774 R775 R777 R778 R779 R780 R781 R782 R783 R784 R785 R7A11 R7A12 R7A18 R7B11 R7B20 R7B9 R7C15 R7C2 R7C4 R7D27 R7D28 R7D36 R7D37 R7D39 R7D41 R7E13 R7E17 R7E22 R7E9 R7F12 R7F21 R7F35 R7F9 R7G114 R7G14 R7G17 R7G2 R7G21 R7G4 R7W1 R7W10 R7W11 R7W12 R7W13 R7W14 R7W16 R7W17 R7W18 R7W5 R7W8 R8B12 R8B14 R8C24 R8D35 R8D43 R8E1 R8E21 R8E25 R8E26 R8E27 R8E28 R8E33 R8E35 R8E37 R8E38 R8F11 R8F18 R8F2 R8F21 R8F38 R8F6 R8G10 R8G13 R8G14 R8G17 R8G18 R8G19 R8G21 R8G22 R8G7 R8G8 R8W10 R8W11 R8W12 R8W13 R8W14 R9A3 R9A8 R9B11 R9B13 R9F27 R9F33 R9F62 R9F64 R9F65 R9F67 R9F69 R9G28 R9G29 R9G32 R9G33 R9G34 R9G4 R9L9 R9M20 R9M21 R9M3 R9M9 R9N16 R9N3 R9P15 R9P16 R9P21 R9P22 R9P32 R9P8 R9R10 R9R11 R9R12 R9R2 R9R9 R9T1 R9T8 R9U1 R9U10 R9U7 |
| 3 | B55.00X01.S033 | 64.10005.55L | CHIP RES 100 F 1/10W 0603 | R2_SA;HF_SA;G_SA; | Released | TAI;RALEC;YAGEO | RM06FTN1000;RTT031000FTP;RC0603FR-07100RL | Multiple |  | Purchase | SMT | 2 | PCS | R1E3 R4E13 |
| 3 | B55.00X01.S033 | 64.10005.6DL | CHIP RES 100 F 1/16W 0402 | R2_SA;HF_SA;G_SA; | Released | TA-I ; RALEC ; CYNTEC ; YAGEO;WALSIN | RM04FTN1000 ; RTT021000FTH ; RR0510S-1000-FN ; RC0402FR-07100RL;WR04X1000FTL | Multiple |  | Purchase | SMT | 52 | PCS | R10W1 R10W6 R1B22 R1C12 R1C4 R1E4 R1E8 R1F2 R1L39 R1L41 R1M3 R1M4 R1U37 R25W165 R2P20 R2T39 R3B4 R3D28 R3D3 R3E1 R3M11 R3M12 R3N20 R3N21 R3P13 R3P49 R3U2 R4C1 R4C5 R4E14 R4E18 R4P11 R4P12 R4P15 R6B2 R6D1 R6N2 R6P46 R6T8 R6T9 R7A13 R7D32 R7P19 R7P30 R8C21 R8C26 R8D42 R9A9 R9F25 R9N2 R9P1 R9U3 |
| 3 | B55.00X01.S033 | 64.10015.L1L | CHIP RES 1K F 1/16W 0402 | R2_SA;HF_SA;G_SA; | Released | TA-I;RALEC;YAGEO | RM04FTN1001 ; RTT021001FTH ; RC0402FR-071KL | Multiple |  | Purchase | SMT | 152 | PCS | R1B1 R1B2 R1C28 R1C32 R1C33 R1C36 R1D36 R1D6 R1D7 R1D8 R1E10 R1E9 R1F5 R1F6 R1G11 R1G15 R1G16 R1G17 R1G2 R1G3 R1L13 R1L23 R1L36 R1L38 R1M19 R1M21 R1T11 R1T29 R1T30 R1U17 R1U30 R1U63 R1U64 R1W25 R25W158 R25W159 R25W160 R25W161 R25W166 R25W167 R25W168 R25W169 R25W170 R25W175 R25W176 R25W177 R25W178 R25W179 R25W180 R2L18 R2L22 R2M4 R2N18 R2P2 R2R5 R2T25 R2T5 R2T50 R2T7 R2U43 R3M10 R3P18 R3P25 R3P32 R3P36 R3P56 R3P8 R3R1 R3R15 R3R2 R4B10 R4C8 R4C9 R4D42 R4D49 R4D58 R4E3 R4E4 R4E5 R4F4 R4F5 R4G14 R4G2 R4G21 R4G22 R4G3 R4R1 R4R6 R4W2 R6L1 R6L12 R6L13 R6L16 R6L2 R6M1 R6M8 R6N13 R6N14 R6N15 R6P16 R6P20 R6P21 R6T5 R6W16 R6W21 R6W23 R7B17 R7B4 R7B5 R7D18 R7D2 R7D26 R7D7 R7E12 R7E20 R7F19 R7F22 R7F27 R7G27 R7G28 R7G29 R7G31 R8A5 R8A6 R8B2 R8B23 R8B30 R8C18 R8C4 R8D21 R8D27 R8D28 R8E2 R8F5 R8W2 R8W3 R8W8 R9A14 R9A15 R9A17 R9B12 R9B14 R9B6 R9B8 R9B9 R9L1 R9L11 R9L2 R9L6 R9L7 R9M1 R9N14 |
| 3 | B55.00X01.S033 | 64.1001D.6DL | CHIP RES 1K B 1/16W 0402 | R2_SA;HF_SA;G_SA; | Released | CYNTEC;RALEC;TAI;YAGEO;WALSIN | RR0510Q-102-BN;RTX021001BETH;RB04BTS1001;RT0402BRE071KL;WF04T1001BTL | Multiple |  | Purchase | SMT | 8 | PCS | R2M6 R2N4 R2T4 R4B9 R4G10 R7B18 R7F17 R8E18 |
| 3 | B55.00X01.S033 | 64.10025.6DL | CHIP RES 10K F 1/16W 0402 | R2_SA;HF_SA;G_SA; | Released | TA-I;RALEC;CYNTEC;YAGEO;WALSIN | RM04FTN1002 ; RTT021002FTH ; RR0510S-103-FN ; RC0402FR-0710KL;WR04X1002FTL | Multiple |  | Purchase | SMT | 97 | PCS | R1C34 R1D10 R1D22 R1D23 R1M11 R1M12 R1M24 R1M25 R1T1 R1U6 R1U7 R1W4 R1W7 R25W174 R25W79 R25W80 R2N13 R2N16 R2N23 R2N28 R2N6 R2N9 R2P15 R2P16 R2P18 R2P19 R2P21 R2P22 R2R1 R2R3 R2T22 R2W1 R3N10 R3T14 R3W5 R3W9 R4A5 R4G17 R4G18 R4G5 R4P5 R5N1 R5N3 R5N5 R6F3 R6L9 R6W2 R6W29 R6W39 R6W40 R7B6 R7C13 R7C20 R7C21 R7C23 R7C5 R7C8 R7D10 R7D12 R7D4 R7D8 R7E5 R7E6 R7F1 R7F14 R7F28 R7F32 R7G22 R7G23 R7G26 R7P13 R8B32 R8D16 R8D30 R8D41 R8D44 R8E34 R8F26 R8F36 R8G20 R8N2 R8N3 R8N5 R9E13 R9E4 R9F12 R9F13 R9F32 R9F61 R9F8 R9P10 R9P5 R9P6 R9W1 R9W12 R9W32 WR8D30 |
| 3 | B55.00X01.S033 | 64.1002D.6DL | CHIP RES 10K B 1/16W 0402(TCR:25PPM) | R2_SA;HF_SA;G_SA; | Released | YAGEO;CYNTEC;TAI;RALEC;WALSIN | RT0402BRD0710KL;RR0510P-103-BN;RB04BTP1002;RTX021002BDTH;WF04U1002BTL | Multiple |  | Purchase | SMT | 3 | PCS | R1D12 R1D19 R9P11 |
| 3 | B55.00X01.S033 | 64.10035.55L | CHIP RES 100K F 1/10W 0603 | R2_SA;HF_SA;G_SA; | Released | TA-I ; RALEC ; YAGEO | RM06FTN1003 ; RTT031003FTP ; RC0603FR-07100KL | Multiple |  | Purchase | SMT | 7 | PCS | R12W14 R12W19 R12W4 R12W9 R5P1 R6W30 RT8P1 |
| 3 | B55.00X01.S033 | 64.10035.6DL | CHIP RES 100K F 1/16W 0402 | R2_SA;HF_SA;G_SA; | Released | TA-I;RALEC;CYNTEC;YAGEO;WALSIN | RM04FTN1003 ; RTT021003FTH ; RR0510S-104-FN ; RC0402FR-07100KL;WR04X1003FTL | Multiple |  | Purchase | SMT | 29 | PCS | R1C13 R1D11 R1D15 R1D18 R1D32 R1D37 R1D39 R1L9 R1U1 R1U2 R1U4 R1U5 R25W142 R25W157 R25W63 R2L25 R2L26 R3P12 R3W2 R4D27 R4D60 R6W35 R8A4 R8B4 R9G26 R9P23 R9P29 R9P33 R9P7 |
| 3 | B55.00X01.S033 | 64.10045.L1L | CHIP RES 1M F 1/16W 0402 | R2_SA;HF_SA;G_SA; | Released | TAI;RALEC;CYNTEC | RM04FTN1004;RTT021004FTH;RR0510S-1004-FN | Multiple |  | Purchase | SMT | 3 | PCS | R1W1 R1W3 R1W6 |
| 3 | B55.00X01.S033 | 64.10055.55L | CHIP RES 10M F 1/10W 0603 | R2_SA;HF_SA;G_SA; | Released | TA-I ; RALEC ; YAGEO | RM06FTN1005 ; RTT031005FTP ; RC0603FR-0710ML | Multiple |  | Purchase | SMT | 1 | PCS | R7C6 |
| 3 | B55.00X01.S033 | 64.10R05.55L | CHIP RES 10 F 1/10W 0603 | R2_SA;HF_SA;G_SA; | Released | TA-I;RALEC;YAGEO;WALSIN | RM06FTN10R0 ; RTT0310R0FTP ; RC0603FR-0710RL;WR06X10R0FTL | Multiple |  | Purchase | SMT | 2 | PCS | R2L8 R9P30 |
| 3 | B55.00X01.S033 | 64.10R05.6DL | CHIP RES 10 F 1/16W 0402 | R2_SA;HF_SA;G_SA; | Released | TAI;RALEC;CYNTEC;YAGEO;WALSIN | RM04FTN10R0;RTT0210R0FTH;RR0510S-100-FN;RC0402FR-0710RL;WR04X10R0FTL | Multiple |  | Purchase | SMT | 46 | PCS | R1B16 R1C21 R1D4 R1D46 R1D47 R1D48 R1D51 R1E1 R1G5 R1L11 R1L14 R1L18 R1L2 R1L20 R1L24 R1L25 R1L30 R1L32 R3N19 R3N9 R3R14 R3R7 R4D39 R4E7 R4E8 R4T3 R4T4 R6N8 R6N9 R6T3 R6T4 R6W26 R6W27 R6W36 R6W37 R7A14 R7A19 R7A7 R7G9 R7M3 R7M8 R8A1 R8B20 R9P26 R9P27 R9R4 |
| 3 | B55.00X01.S033 | 64.11025.6DL | CHIP RES 11K F 1/16W 0402 | R2_SA;HF_SA;G_SA; | Released | TA-I ; RALEC ; CYNTEC ; YAGEO;WALSIN | RM04FTN1102 ; RTT021102FTH ; RR0510S-1102-FN ; RC0402FR-0711KL;WR04X1102FTL | Multiple |  | Purchase | SMT | 1 | PCS | R1D42 |
| 3 | B55.00X01.S033 | 64.11305.6DL | CHIP RES 113 F 1/16W 0402 | R2_SA;HF_SA;G_SA; | Released | TA-I;RALEC;CYNTEC;YAGEO | RM04FTN1130;RTT021130FTH;RR0510S-1130-FN;RC0402FR-07113RL | Multiple |  | Purchase | SMT | 1 | PCS | R8B9 |
| 3 | B55.00X01.S033 | 64.12005.55L | CHIP RES 120 F 1/10W 0603 | R2_SA;HF_SA;G_SA; | Released | TA-I ; RALEC ; YAGEO | RM06FTN1200 ; RTT031200FTP ; RC0603FR-07120RL | Multiple |  | Purchase | SMT | 8 | PCS | R1A1 R1G20 R3U4 R4B2 R4G6 R4L4 R7B10 R7F10 |
| 3 | B55.00X01.S033 | 64.12005.6DL | CHIP RES 120 F 1/16W 0402 | R2_SA;HF_SA;G_SA; | Released | TAI;RALEC;CYNTEC;YAGEO | RM04FTN1200;RTT021200FTH;RR0510S-121-FN;RC0402FR-07120RL | Multiple |  | Purchase | SMT | 49 | PCS | R1L21 R25W1 R25W10 R25W11 R25W12 R25W13 R25W14 R25W15 R25W16 R25W17 R25W18 R25W19 R25W2 R25W20 R25W21 R25W22 R25W23 R25W24 R25W25 R25W26 R25W27 R25W28 R25W31 R25W32 R25W33 R25W34 R25W35 R25W36 R25W37 R25W38 R25W39 R25W40 R25W41 R25W42 R25W43 R25W44 R25W45 R25W46 R25W47 R25W48 R25W49 R25W5 R25W50 R25W51 R25W52 R25W6 R25W7 R25W8 R25W9 |
| 3 | B55.00X01.S033 | 64.12125.6DL | CHIP RES 12.1K F 1/16W 0402 | R2_SA;HF_SA;G_SA; | Released | TA-I ; RALEC ; CYNTEC ; YAGEO ; WALSIN | RM04FTN1212 ; RTT021212FTH ; RR0510S-1212-FN ; RC0402FR-0712K1L ; WR04X1212FTL | Multiple |  | Purchase | SMT | 1 | PCS | R9P24 |
| 3 | B55.00X01.S033 | 64.13715.6DL | CHIP RES 1.37K F 1/16W 0402 | R2_SA;HF_SA;G_SA; | Released | TA-I;RALEC;CYNTEC;YAGEO | RM04FTN1371;RTT021371FTH;RR0510S-1371-FN;RC0402FR-071K37L | Multiple |  | Purchase | SMT | 5 | PCS | R7E16 R8D15 R8D17 R8W6 R8W7 |
| 3 | B55.00X01.S033 | 64.15005.6DL | CHIP RES 150 F 1/16W 0402 | R2_SA;HF_SA;G_SA; | Released | TAI;RALEC;CYNTEC;YAGEO;WALSIN | RM04FTN1500 ; RTT021500FTH ; RR0510S-1500-FN ; RC0402FR-07150RL;WR04X1500FTL | Multiple |  | Purchase | SMT | 41 | PCS | R1B8 R1D9 R1G7 R1L15 R1L17 R1U35 R1U41 R25W123 R25W124 R25W125 R25W126 R25W127 R25W128 R2T72 R2T73 R2U40 R2U41 R3P15 R4D51 R4E6 R4P17 R4P20 R4P23 R4P24 R4R2 R4R3 R4R4 R6D9 R6T6 R6T7 R7A17 R7G24 R7P18 R7P20 R7P21 R7P27 R7P28 R7P5 R8A13 R8A14 R9A11 |
| 3 | B55.00X01.S033 | 64.15015.6DL | CHIP RES 1.5K F 1/16W 0402 | R2_SA;HF_SA;G_SA; | Released | TA-I;RALEC;CYNTEC;YAGEO;WALSIN | RM04FTN1501 ; RTT021501FTH ; RR0510S-152-FN ; RC0402FR-071K5L;WR04X1501FTL | Multiple |  | Purchase | SMT | 8 | PCS | R1C16 R2L10 R2M8 R2N29 R32W2 R3P16 R4D32 R4D57 |
| 3 | B55.00X01.S033 | 64.15025.6DL | CHIP RES 15K F 1/16W 0402 | R2_SA;HF_SA;G_SA; | Released | TA-I;RALEC;CYNTEC;YAGEO | RM04FTN1502;RTT021502FTH;RR0510S-153-FN;RC0402FR-0715KL | Multiple |  | Purchase | SMT | 2 | PCS | R9P18 R9T6 |
| 3 | B55.00X01.S033 | 64.15035.6DL | CHIP RES 150K F 1/16W 0402 | R2_SA;HF_SA;G_SA; | Released | TA-I;RALEC;CYNTEC;YAGEO;WALSIN | RM04FTN1503 ; RTT021503FTH ; RR0510S-154-FN ; RC0402FR-07150KL;WR04X1503FTL | Multiple |  | Purchase | SMT | 1 | PCS | R9P17 |
| 3 | B55.00X01.S033 | 64.16025.6DL | CHIP RES 16K F 1/16W 0402 | R2_SA;HF_SA;G_SA; | Released | TA-I ; RALEC ; CYNTEC ; YAGEO | RM04FTN1602 ; RTT021602FTH ; RR0510S-163-FN ; RC0402FR-0716KL | Multiple |  | Purchase | SMT | 4 | PCS | R1B12 R1D34 R3N29 R7A10 |
| 3 | B55.00X01.S033 | 64.16535.6DL | CHIP RES 165K F 1/16W 0402 | R2_SA;HF_SA;G_SA; | Released | TA-I;RALEC;CYNTEC;YAGEO | RM04FTN1653;RTT021653FTH;RR0510S-1653-FN;RC0402FR-07165KL | Multiple |  | Purchase | SMT | 1 | PCS | R1D14 |
| 3 | B55.00X01.S033 | 64.16905.6DL | CHIP RES 169 F 1/16W 0402 | R2_SA;HF_SA;G_SA; | Released | TA-I;RALEC;CYNTEC;YAGEO | RM04FTN1690;RTT021690FTH;RR0510S-1690-FN;RC0402FR-07169RL | Multiple |  | Purchase | SMT | 1 | PCS | R3N1 |
| 3 | B55.00X01.S033 | 64.18015.6DL | CHIP RES 1.8K F 1/16W 0402 | R2_SA;HF_SA;G_SA; | Released | TAI;RALEC;CYNTEC;YAGEO | RM04FTN1801;RTT021801FTH;RR0510S-182-FN ;RC0402FR-071K8L | Multiple |  | Purchase | SMT | 8 | PCS | R5N2 R5N4 R8B11 R8B13 R8B6 R8B7 R8N1 R8N4 |
| 3 | B55.00X01.S033 | 64.18025.6DL | CHIP RES 18K F 1/16W 0402 | R2_SA;HF_SA;G_SA; | Released | TA-I;RALEC;CYNTEC;YAGEO;WALSIN | RM04FTN1802;RTT021802FTH;RR0510S-1802-FN;RC0402FR-0718KL;WR04X1802FTL | Multiple |  | Purchase | SMT | 1 | PCS | R25W58 |
| 3 | B55.00X01.S033 | 64.18215.6DL | CHIP RES 1.82K F 1/16W 0402 | R2_SA;HF_SA;G_SA; | Released | RALEC ; CYNTEC ; TA-I ; YAGEO | RTT021821FTH ; RR0510S-1821-FN ; RM04FTN1821 ; RC0402FR-071K82L | Multiple |  | Purchase | SMT | 2 | PCS | R1U28 R1U44 |
| 3 | B55.00X01.S033 | 64.20005.6DL | CHIP RES 200 F 1/16W 0402 | R2_SA;HF_SA;G_SA; | Released | TA-I;RALEC;CYNTEC;WALSIN;YAGEO | RM04FTN2000;RTT022000FTH;RR0510S-201-FN;WR04X2000FTL;RC0402FR-07200RL | Multiple |  | Purchase | SMT | 10 | PCS | R1L22 R1L31 R1M14 R2R9 R2T19 R2T26 R2T37 R9E10 R9E11 R9E12 |
| 3 | B55.00X01.S033 | 64.20005.L0L | CHIP RES 200 F 1/16W 0402 13" REEL | R2_SA;HF_SA;G_SA; | Released | RALEC;TA-I;YAGEO;WALSIN | RTT022000FH5;RM04FLN2000;RC0402FR-13200RL;WR04X2000FHL | Multiple |  | Purchase | SMT | 1 | PCS | R25W67 |
| 3 | B55.00X01.S033 | 64.20015.6DL | CHIP RES 2K F 1/16W 0402 | R2_SA;HF_SA;G_SA; | Released | TA-I;RALEC;CYNTEC;YAGEO;WALSIN | RM04FTN2001 ; RTT022001FTH ; RR0510S-202-FN ; RC0402FR-072KL;WR04X2001FTL | Multiple |  | Purchase | SMT | 18 | PCS | R2L11 R2L12 R2L15 R2L21 R2L23 R2L4 R2L5 R2L6 R32W5 R32W6 R32W7 R3N3 R8C15 R8C16 R9M16 R9M17 R9W16 R9W17 |
| 3 | B55.00X01.S033 | 64.20025.6DL | CHIP RES 20K F 1/16W 0402 | R2_SA;HF_SA;G_SA; | Released | TA-I;RALEC;CYNTEC;YAGEO;WALSIN | RM04FTN2002 ; RTT022002FTH ; RR0510S-203-FN ; RC0402FR-0720KL;WR04X2002FTL | Multiple |  | Purchase | SMT | 10 | PCS | R3N4 R4B5 R4G7 R6W38 R7B15 R7C10 R7F13 R8D40 R8E16 R9A5 |
| 3 | B55.00X01.S033 | 64.20035.6DL | CHIP RES 200K F 1/16W 0402 | R2_SA;HF_SA;G_SA; | Released | TA-I;RALEC;CYNTEC;YAGEO;WALSIN | RM04FTN2003 ; RTT022003FTH ; RR0510S-204-FN ; RC0402FR-07200KL;WR04X2003FTL | Multiple |  | Purchase | SMT | 2 | PCS | R1D20 R1U50 |
| 3 | B55.00X01.S033 | 64.20R05.6DL | CHIP RES 20 F 1/16W 0402 | R2_SA;HF_SA;G_SA; | Released | TA-I;RALEC;CYNTEC;YAGEO | RM04FTN20R0;RTT0220R0FTH;RR0510S-200-FN;RC0402FR-0720RL | Multiple |  | Purchase | SMT | 54 | PCS | R1M8 R1M9 R1T7 R1T8 R1U10 R1U19 R1U20 R1U9 R25W121 R25W122 R2T49 R2U1 R2U10 R2U31 R2U32 R2U33 R2U34 R2U6 R2U7 R2U9 R3R8 R3R9 R4T10 R4T9 R6U13 R6U14 R6W20 R6W22 R7M4 R7M5 R8C11 R8C12 R8C14 R8C20 R8D23 R8D24 R8D4 R8D7 R8G4 R8G5 R8W4 R8W5 R9F22 R9F23 R9G12 R9G13 R9G14 R9G15 R9M13 R9M14 R9R7 R9R8 R9W13 R9W14 |
| 3 | B55.00X01.S033 | 64.21515.6DL | CHIP RES 2.15K F 1/16W 0402 | R2_SA;HF_SA;G_SA; | Released | CYNTEC; RALEC; TAI; YAGEO | RR0510S2151FN; RTT022151FTH; RM04FTN2151; RC0402FR-072K15L | Multiple |  | Purchase | SMT | 2 | PCS | R8E30 R8E36 |
| 3 | B55.00X01.S033 | 64.21525.6DL | CHIP RES 21.5K F 1/16W 0402 | R2_SA;HF_SA;G_SA; | Released | TA-I;RALEC;CYNTEC;YAGEO | RM04FTN2152;RTT022152FTH;RR0510S-2152-FN;RC0402FR-0721K5L | Multiple |  | Purchase | SMT | 1 | PCS | R9W31 |
| 3 | B55.00X01.S033 | 64.22105.6DL | CHIP RES 221 F 1/16W 0402 | R2_SA;HF_SA;G_SA; | Released | TA-I;RALEC;CYNTEC;YAGEO | RM04FTN2210;RTT022210FTH;RR0510S-2210-FN;RC0402FR-07221RL | Multiple |  | Purchase | SMT | 11 | PCS | R10W4 R1C1 R1L33 R2U42 R2U44 R3B1 R6B3 R6N10 R9A20 R9E24 R9F28 |
| 3 | B55.00X01.S033 | 64.22115.6DL | CHIP RES 2.21K F 1/16W 0402 | R2_SA;HF_SA;G_SA; | Released | TA-I ; RALEC ; CYNTEC ; YAGEO | RM04FTN2211 ; RTT022211FTH ; RR0510S-2211-FN ; RC0402FR-072K21L | Multiple |  | Purchase | SMT | 14 | PCS | R1R16 R1R17 R1R18 R1R19 R1R20 R1R21 R1R22 R1R23 R2T29 R4U2 R8F23 R9A12 R9A16 R9A7 |
| 3 | B55.00X01.S033 | 64.22615.6DL | CHIP RES 2.26K F 1/16W 0402 | R2_SA;HF_SA;G_SA; | Released | TA-I;RALEC;CYNTEC;YAGEO | RM04FTN2261;RTT022261FTH;RR0510S-2261-FN;RC0402FR-072K26L | Multiple |  | Purchase | SMT | 11 | PCS | R1B13 R1G6 R2U13 R2U5 R3P61 R7A8 R7A9 R7D5 R7D9 R7F36 R7G10 |
| 3 | B55.00X01.S033 | 64.22R15.6DL | CHIP RES 22.1 F 1/16W 0402 | R2_SA;HF_SA;G_SA; | Released | TA-I;CYNTEC;RALEC;YAGEO | RM04FTN22R1;RR0510S-22R1-FN;RTT0222R1FTH;RC0402FR-0722R1L | Multiple |  | Purchase | SMT | 28 | PCS | R1C30 R1T9 R1W9 R25W78 R25W85 R25W86 R25W87 R25W88 R25W89 R25W90 R2L16 R2T41 R2T42 R2T46 R3P20 R4B7 R4D46 R4D63 R4G12 R7B12 R7E15 R7F16 R8A11 R8E7 R8F10 R8G1 R8G24 R9F11 |
| 3 | B55.00X01.S033 | 64.23225.6DL | CHIP RES 23.2K F 1/16W 0402 | R2_SA;HF_SA;G_SA; | Released | CYNTEC;RALEC;TAI;YAGEO | RR0510S-2322-FN;RTT022322FTH;RM04FTN2322;RC0402FR-0723K2L | Multiple |  | Purchase | SMT | 1 | PCS | R8E31 |
| 3 | B55.00X01.S033 | 64.23235.L0L | CHIP RES 232K F 1/16W 0402 | R2_SA;HF_SA;G_SA; | Released | TA-I;RALEC;CYNTEC | RM04FTN2323;RTT022323FTH;RR0510S-2323-FN | Multiple |  | Purchase | SMT | 1 | PCS | R6W3 |
| 3 | B55.00X01.S033 | 64.24005.6DL | CHIP RES 240 F 1/16W 0402(ROHS | R2_SA;HF_SA;G_SA; | Released | TA-I ; RALEC ; CYNTEC ; YAGEO | RM04FTN2400 ; RTT022400FTH ; RR0510S-241-FN ; RC0402FR-07240RL | Multiple |  | Purchase | SMT | 21 | PCS | R1T27 R25W117 R3D24 R3P60 R3R13 R4C10 R4P14 R4P21 R4T5 R4T6 R5D3 R5D4 R6T1 R6T2 R7M2 R7M7 R7P14 R9M18 R9M19 R9W18 R9W19 |
| 3 | B55.00X01.S033 | 64.24925.6DL | CHIP RES 24.9K F 1/16W 0402 | R2_SA;HF_SA;G_SA; | Released | TA-I ; RALEC ; CYNTEC ; YAGEO ; WALSIN | RM04FTN2492 ; RTT022492FTH ; RR0510S-2492-FN ; RC0402FR-0724K9L ; WR04X2492FTL | Multiple |  | Purchase | SMT | 1 | PCS | R8E39 |
| 3 | B55.00X01.S033 | 64.26715.6DL | CHIP RES 2.67K F 1/16W 0402 | R2_SA;HF_SA;G_SA; | Released | TA-I ; RALEC ; CYNTEC ; YAGEO | RM04FTN2671 ; RTT022671FTH ; RR0510S-2671-FN ; RC0402FR-072K67L | Multiple |  | Purchase | SMT | 1 | PCS | R8A2 |
| 3 | B55.00X01.S033 | 64.27015.6DL | CHIP RES 2.7K F 1/16W 0402 | R2_SA;HF_SA;G_SA; | Released | TAI;RALEC;CYNTEC;YAGEO | RM04FTN2701;RTT022701FTH;RR0510S-2701-FN;RC0402FR-072K7L | Multiple |  | Purchase | SMT | 10 | PCS | R1T4 R1T6 R1U21 R1U22 R1U23 R1U49 R25W30 R9G35 R9P20 R9P4 |
| 3 | B55.00X01.S033 | 64.27035.6DL | CHIP RES 270K F 1/16W 0402 | R2_SA;HF_SA;G_SA; | Released | TAI;RALEC;CYNTEC;YAGEO;WALSIN | RM04FTN2703;RTT022703FTH;RR0510S-2703-FN;RC0402FR-07270KL;WR04X27031FTL | Multiple |  | Purchase | SMT | 1 | PCS | R9P13 |
| 3 | B55.00X01.S033 | 64.27R45.6DL | CHIP RES 27.4 F 1/16W 0402 | R2_SA;HF_SA;G_SA; | Released | TA-I;RALEC;CYNTEC;YAGEO;WALSIN | RM04FTN27R4 ; RTT0227R4FTH ; RR0510S-27R4-FN ; RC0402FR-0727R4L;WR04X27R4FTL | Multiple |  | Purchase | SMT | 24 | PCS | R4D1 R4D10 R4D11 R4D12 R4D13 R4D14 R4D16 R4D17 R4D19 R4D2 R4D20 R4D21 R4D22 R4D23 R4D25 R4D28 R4D29 R4D3 R4D4 R4D5 R4D6 R4D7 R4D8 R4D9 |
| 3 | B55.00X01.S033 | 64.2R005.6DL | CHIP RES 2 F 1/16W 0402 | R2_SA;HF_SA;G_SA; | Released | RALEC;CYNTEC;TA-I;YAGEO;WALSIN | RTT022R00FTH;RR0510S-2R0-FNH;RM04FTN2R00;RC0402FR-072RL;WR04W2R00FTL | Multiple |  | Purchase | SMT | 12 | PCS | R1F4 R1G1 R1G14 R4F3 R4G1 R4G20 R6L14 R6L3 R6M2 R9L3 R9L8 R9M2 |
| 3 | B55.00X01.S033 | 64.2R205.55L | CHIP RES 2.2 F 1/10W 0603 | R2_SA;HF_SA;G_SA; | Released | TAI;YAGEO;RALEC;WALSIN | RM06FTN2R20;RC0603FR-072R2L;RTT032R20FTP;WR06W2R20FTL | Multiple |  | Purchase | SMT | 5 | PCS | R2T21 R2T23 R2T52 R3D14 R6P25 |
| 3 | B55.00X01.S033 | 64.30105.6DL | CHIP RES 301 F 1/16W 0402 | R2_SA;HF_SA;G_SA; | Released | TA-I;RALEC;CYNTEC;YAGEO | RM04FTN3010;RTT023010FTH;RR0510S-3010-FN;RC0402FR-07301RL | Multiple |  | Purchase | SMT | 1 | PCS | R1L37 |
| 3 | B55.00X01.S033 | 64.31615.6DL | CHIP RES 3.16K F 1/16W 0402 | R2_SA;HF_SA;G_SA; | Released | TAI;RALEC;CYNTEC;YAGEO;WALSIN | RM04FTN3161;RTT023161FTH;RR0510S-3161-FN;RC0402FR-073K16L;WR04X3161FTL | Multiple |  | Purchase | SMT | 7 | PCS | R1B15 R1G22 R3N31 R4C11 R4D64 R4E2 R9N7 |
| 3 | B55.00X01.S033 | 64.33215.6DL | CHIP RES 3.32K F 1/16W 0402 | R2_SA;HF_SA;G_SA; | Released | TAI;RALEC;YAGEO;CYNTEC;WALSIN | RM04FTN3321;RTT023321FTH;RC0402FR-073K32L;RR0510S-3321-FN;WR04X3321FTL | Multiple |  | Purchase | SMT | 1 | PCS | R9E7 |
| 3 | B55.00X01.S033 | 64.33R25.6DL | CHIP RES 33.2 F 1/16W 0402 | R2_SA;HF_SA;G_SA; | Released | TA-I;RALEC;CYNTEC;YAGEO | RM04FTN33R2;RTT0233R2FTH;RR0510S-33R2-FN;RC0402FR-0733R2L | Multiple |  | Purchase | SMT | 79 | PCS | R1B4 R1D1 R1D26 R1D30 R1D33 R1G8 R1L26 R1L29 R1U34 R1U36 R1U46 R25W133 R25W136 R25W138 R25W139 R25W68 R25W69 R25W70 R25W72 R25W73 R25W75 R25W81 R25W82 R2M1 R2M3 R2M7 R2N1 R2N26 R2P4 R2R10 R2R2 R2T28 R2T30 R2T33 R2T38 R2T47 R3N24 R3N26 R3P42 R3P43 R3P46 R3R3 R4A4 R4A6 R4D65 R4G15 R4G19 R6P45 R7B1 R7C14 R7C16 R7C26 R7D24 R7D25 R7D29 R7D31 R7D34 R7F23 R7F29 R7F3 R7F37 R7F4 R8D11 R8D22 R8E10 R8E13 R8E17 R8E20 R8E24 R8E5 R8E9 R8F12 R8F27 R8F29 R8F8 R9A13 R9G31 R9P3 RN8F5 |
| 3 | B55.00X01.S033 | 64.34805.6DL | CHIP RES 348 F 1/16W 0402 | R2_SA;HF_SA;G_SA; | Released | TAI;CYNTEC;YAGEO;RALEC | RM04FTN3480;RR0510S-3480-FN;RC0402FR-07348RL;RTT023480FTH | Multiple |  | Purchase | SMT | 1 | PCS | R7D15 |
| 3 | B55.00X01.S033 | 64.34815.6DL | CHIP RES 3.48K F 1/16W 0402 | R2_SA;HF_SA;G_SA; | Released | TA-I;RALEC;CYNTEC;YAGEO | RM04FTN3481;RTT023481FTH;RR0510S-3481-FN;RC0402FR-073K48L | Multiple |  | Purchase | SMT | 2 | PCS | R1U27 R1U38 |
| 3 | B55.00X01.S033 | 64.37405.6DL | CHIP RES 374 F 1/16W0402 (ROHS | R2_SA;HF_SA;G_SA; | Released | TAI;YAGEO;RALEC;CYNTEC | RM04FTN3740;RC0402FR-07374RL;RTT023740FTH;RR0510S-3740-FN | Multiple |  | Purchase | SMT | 5 | PCS | R1U43 R25W183 R2T36 R3P45 R7D33 |
| 3 | B55.00X01.S033 | 64.37415.6DL | CHIP RES 3.74K F 1/16W 0402 | R2_SA;HF_SA;G_SA; | Released | TA-I ; RALEC ; CYNTEC ; YAGEO ; WALSIN | RM04FTN3741;RTT023741FTH;RR0510S-3741-FN;RC0402FR-073K74L;WR04X3741FTL | Multiple |  | Purchase | SMT | 1 | PCS | R9P9 |
| 3 | B55.00X01.S033 | 64.39015.6DL | CHIP RES 3.9K F 1/16W 0402 | R2_SA;HF_SA;G_SA; | Released | TA-I;RALEC;CYNTEC;YAGEO;WALSIN | RM04FTN3901;RTT023901FTH;RR0510S-3901-FN;RC0402FR-073K9L;WR04X3901FTL | Multiple |  | Purchase | SMT | 4 | PCS | R4B6 R4G11 R7B14 R7F15 |
| 3 | B55.00X01.S033 | 64.40215.6DL | CHIP RES 4.02K F 1/16W 0402 | R2_SA;HF_SA;G_SA; | Released | TA-I;RALEC;CYNTEC;YAGEO;WALSIN | RM04FTN4021;RTT024021FTH;RR0510S-4021-FN;RC0402FR-074K02L;WR04X4021FTL | Multiple |  | Purchase | SMT | 7 | PCS | R2L9 R32W1 R3N22 R6P27 R6P28 R7C24 R9N8 |
| 3 | B55.00X01.S033 | 64.40225.6DL | CHIP RES 40.2K F 1/16W 0402 | R2_SA;HF_SA;G_SA; | Released | TA-I;RALEC;CYNTEC;YAGEO | RM04FTN4022;RTT024022FTH;RR0510S-4022-FN;RC0402FR-0740K2L | Multiple |  | Purchase | SMT | 2 | PCS | R1D40 R6W49 |
| 3 | B55.00X01.S033 | 64.44215.6DL | CHIP RES 4.42K F 1/16W 0402(RO | R2_SA;HF_SA;G_SA; | Released | CYNTEC;RALTEC;TAI;WALSIN;YAGEO | RR0510S-4421-FN;RTT024421FTH;RM04FTN4421;WR04X4421FTL;RC0402FR-074K42L | Multiple |  | Purchase | SMT | 1 | PCS | R9F6 |
| 3 | B55.00X01.S033 | 64.47025.6DL | CHIP RES 47K F 1/16W 0402 | R2_SA;HF_SA;G_SA; | Released | TA-I;RALEC;CYNTEC;YAGEO;WALSIN | RM04FTN4702;RTT024702FTH;RR0510S-473-FN;RC0402FR-0747KL;WR04X4702FTL | Multiple |  | Purchase | SMT | 1 | PCS | R3W4 |
| 3 | B55.00X01.S033 | 64.47035.L0L | CHIP RES 470K F 1/16W 0402 (YAMA) | R2_SA;HF_SA;G_SA; | Released | TAI;RALEC;CYNTEC | RM04FTN4703;RTT024703FTH;RR0510S-474-FN | Multiple |  | Purchase | SMT | 1 | PCS | R3W1 |
| 3 | B55.00X01.S033 | 64.47505.55L | CHIP RES 475 F 1/10W 0603 | R2_SA;HF_SA;G_SA; | Released | TA-I ; RALEC ; YAGEO | RM06FTN4750 ; RTT034750FTP ; RC0603FR-07475RL | Multiple |  | Purchase | SMT | 1 | PCS | R8A12 |
| 3 | B55.00X01.S033 | 64.47505.6DL | CHIP RES 475 F 1/16W 0402 | R2_SA;HF_SA;G_SA; | Released | TA-I;RALEC;CYNTEC;YAGEO;WALSIN | RM04FTN4750 ; RTT024750FTH ; RR0510S-4750-FN ; RC0402FR-07475RL;WR04X4750FTL | Multiple |  | Purchase | SMT | 2 | PCS | R8F25 R9A4 |
| 3 | B55.00X01.S033 | 64.47515.6DL | CHIP RES 4.75K F 1/16W 0402 | R2_SA;HF_SA;G_SA; | Released | TA-I;RALEC;CYNTEC;YAGEO | RM04FTN4751;RTT024751FTH;RR0510S-4751-FN;RC0402FR-074K75L | Multiple |  | Purchase | SMT | 155 | PCS | R10W2 R10W3 R10W7 R1B21 R1D21 R1D35 R1E12 R1F1 R1L19 R1L27 R1L7 R1R5 R1W36 R1W37 R1W42 R1W43 R1W44 R1W45 R25W100 R25W104 R25W107 R25W109 R25W115 R25W129 R25W130 R25W131 R25W132 R25W134 R25W135 R25W146 R25W148 R25W149 R25W150 R25W151 R25W152 R25W153 R25W185 R25W94 R25W95 R25W96 R2M2 R2M5 R2N27 R2N32 R2N7 R2P13 R2P17 R2P3 R2P5 R2P8 R2R7 R2T3 R2T34 R2T35 R2T6 R2U2 R2U4 R2U48 R3N11 R3N12 R3N13 R3P44 R3P53 R3R10 R3R16 R3R4 R3W6 R3W7 R4D40 R4D41 R4D69 R4D70 R4R5 R4U1 R4U3 R4W1 R4W6 R6M4 R6M9 R6P39 R6P48 R6W1 R6W10 R6W11 R6W12 R6W24 R6W25 R6W28 R6W4 R6W41 R6W44 R6W45 R6W46 R6W5 R6W6 R7C17 R7D3 R7D30 R7D42 R7D44 R7D6 R7E10 R7E11 R7E21 R7E7 R7F33 R7F5 R7G7 R7W19 R7W21 R8B10 R8B16 R8B17 R8B18 R8B19 R8B25 R8B3 R8B31 R8B5 R8B8 R8C1 R8C2 R8C25 R8C6 R8C7 R8C9 R8D14 R8D25 R8D26 R8D29 R8D31 R8D37 R8E14 R8E22 R8E23 R8E3 R8E32 R8F13 R8F14 R8F24 R8F34 R8G2 R8G23 R8W15 R8W9 R9A18 R9A21 R9E21 R9F3 R9F30 R9F52 R9F55 R9T9 RN8F1 RN8F3 |
| 3 | B55.00X01.S033 | 64.49915.6DL | CHIP RES 4.99K F 1/16W 0402 | R2_SA;HF_SA;G_SA; | Released | TA-I;RALEC;CYNTEC;YAGEO;WALSIN | RM04FTN4991 ; RTT024991FTH ; RR0510S-4991-FN ; RC0402FR-074K99L ; WR04X4991FTL | Multiple |  | Purchase | SMT | 1 | PCS | R9P12 |
| 3 | B55.00X01.S033 | 64.49925.6DL | CHIP RES 49.9K F 1/16W 0402 | R2_SA;HF_SA;G_SA; | Released | TA-I ; RALEC ; CYNTEC ; YAGEO ; WALSIN | RM04FTN4992 ; RTT024992FTH ; RR0510S-4992-FN ; RC0402FR-0749K9L ; WR04X4992FTL | Multiple |  | Purchase | SMT | 4 | PCS | R25W57 R2L19 R8D39 R8F9 |
| 3 | B55.00X01.S033 | 64.49R95.6DL | CHIP RES 49.9 F 1/16W 0402 | R2_SA;HF_SA;G_SA; | Released | TA-I;RALEC;CYNTEC;YAGEO;WALSIN | RM04FTN49R9;RTT0249R9FTH;RR0510S-49R9-FN;RC0402FR-0749R9L;WR04X49R9FTL | Multiple |  | Purchase | SMT | 54 | PCS | R1L16 R1T28 R1T40 R2N19 R2N22 R2N31 R2T18 R3B2 R3D15 R3D19 R3D20 R3D4 R3D9 R3P17 R3T11 R4P18 R4P19 R4P2 R4P3 R4P4 R5P2 R5P3 R5P4 R5R1 R6B1 R6D11 R6D12 R6D2 R6D5 R6D8 R6F1 R6F2 R6F4 R6F5 R6N1 R7P10 R7P11 R7P25 R7P26 R7P8 R8B29 R8D19 R8D20 R8P1 R8P2 R8P3 R8R1 R9B4 R9B5 R9N1 R9P2 R9R5 R9R6 R9U4 |
| 3 | B55.00X01.S033 | 64.4R025.6DL | CHIP RES 4.02 F 1/16W 0402 | R2_SA;HF_SA;G_SA; | Released | RALEC;CYNTEC;TAI;YAGEO;WALSIN | RTT024R02FTH;RR0510S-4R02-FNH;RM04FTN4R02;RC0402FR-074R02L;WR04W4R02FTL | Multiple |  | Purchase | SMT | 4 | PCS | R12W13 R12W18 R12W3 R12W8 |
| 3 | B55.00X01.S033 | 64.51015.6DL | CHIP RES 5.1K F 1/16W 0402 | R2_SA;HF_SA;G_SA; | Released | TA-I;RALEC;CYNTEC;YAGEO;WALSIN | RM04FTN5101 ; RTT025101FTH ; RR0510S-512-FN ; RC0402FR-075K1L;WR04X5101FTL | Multiple |  | Purchase | SMT | 1 | PCS | R9F31 |
| 3 | B55.00X01.S033 | 64.51115.6DL | CHIP RES 5.11K F 1/16W 0402 | R2_SA;HF_SA;G_SA; | Released | TA-I ; RALEC ; CYNTEC ; YAGEO;WALSIN | RM04FTN5111 ; RTT025111FTH ; RR0510S-5111-FN ; RC0402FR-075K11L;WR04X5111FTL | Multiple |  | Purchase | SMT | 6 | PCS | R1U26 R1U29 R1U32 R1U39 R1U47 R8A10 |
| 3 | B55.00X01.S033 | 64.51135.6DL | CHIP RES 511K F 1/16W 0402 | R2_SA;HF_SA;G_SA; | Released | TAI ; RALEC ; CYNTEC ; YAGEO | RM04FTN5113;RTT025113FTH;RR0510S-5113-FN;RC0402FR-07511KL | Multiple |  | Purchase | SMT | 1 | PCS | R8D38 |
| 3 | B55.00X01.S033 | 64.51R15.6DL | CHIP RES 51.1 F 1/16W 0402 | R2_SA;HF_SA;G_SA; | Released | TA-I;RALEC;CYNTEC;YAGEO | RM04FTN51R1;RTT0251R1FTH;RR0510S-51R1-FN;RC0402FR-0751R1L | Multiple |  | Purchase | SMT | 7 | PCS | R2N25 R6N4 R7C3 R7P29 R7R1 R8B1 R9N4 |
| 3 | B55.00X01.S033 | 64.61915.6DL | CHIP RES 6.19K F 1/16W 0402 | R2_SA;HF_SA;G_SA; | Released | TA-I;RALEC;CYNTEC;YAGEO;WALSIN | RM04FTN6191;RTT026191FTH;RR0510S-6191-FN;RC0402FR-076K19L;WR04X6191FTL | Multiple |  | Purchase | SMT | 6 | PCS | R1D31 R4B4 R4G9 R7B13 R7F11 R9T3 |
| 3 | B55.00X01.S033 | 64.63415.6DL | CHIP RES 6.34K F 1/16W 0402 | R2_SA;HF_SA;G_SA; | Released | TA-I;RALEC;CYNTEC;YAGEO | RM04FTN6341;RTT026341FTH;RR0510S-6341-FN;RC0402FR-076K34L | Multiple |  | Purchase | SMT | 1 | PCS | R3P51 |
| 3 | B55.00X01.S033 | 64.63425.6DL | CHIP RES 63.4K F 1/16W 0402 | R2_SA;HF_SA;G_SA; | Released | YAGEO;TAI;RALEC;CYNTEC | RC0402FR-0763K4L;RM04FTN6342;RTT026342FTH ;RR0510S-6342-FN | Multiple |  | Purchase | SMT | 1 | PCS | R2L20 |
| 3 | B55.00X01.S033 | 64.64905.6DL | CHIP RES 649 F 1/16W 0402 | R2_SA;HF_SA;G_SA; | Released | TA-I;RALEC;CYNTEC;YAGEO | RM04FTN6490;RTT026490FTH;RR0510S-6490-FN;RC0402FR-07649RL | Multiple |  | Purchase | SMT | 1 | PCS | R1U33 |
| 3 | B55.00X01.S033 | 64.64R95.6DL | CHIP RES 64.9 F 1/16W 0402 | R2_SA;HF_SA;G_SA; | Released | RALEC;YAGEO;TAI;CYNTEC | RTT0264R9FTH;RC0402FR-0764R9L;RM04FTN64R9;RR0510S-64R9-FN | Multiple |  | Purchase | SMT | 4 | PCS | R3D21 R3P29 R3P38 R7M9 |
| 3 | B55.00X01.S033 | 64.66505.6DL | CHIP RES 665 F 1/16W 0402 | R2_SA;HF_SA;G_SA; | Released | TAI;YAGEO;RALEC;CYNTEC;WALSIN | RM04FTN6650;RC0402FR-07665RL;RTT026650FTH;RR0510S-6650-FN;WR04X6650F}T,L | Multiple |  | Purchase | SMT | 18 | PCS | R1T2 R1T3 R2N5 R2N8 R2T53 R2T54 R2U11 R2U3 R2U38 R2U39 R3R12 R3R5 R4T7 R4T8 R6U17 R6U18 R7M1 R7M6 |
| 3 | B55.00X01.S033 | 64.69825.6DL | CHIP RES 69.8K F 1/16W 0402 | R2_SA;HF_SA;G_SA; | Released | TA-I;RALEC;CYNTEC;YAGEO | RM04FTN6982;RTT026982FTH;RR0510S-6982-FN;RC0402FR-0769K8L | Multiple |  | Purchase | SMT | 1 | PCS | R1D16 |
| 3 | B55.00X01.S033 | 64.75025.6DL | CHIP RES 75K F 1/16W 0402 | R2_SA;HF_SA;G_SA; | Released | TA-I;RALEC;CYNTEC;YAGEO;WALSIN | RM04FTN7502;RTT027502FTH;RR0510S-753-FN;RC0402FR-0775KL;WR04X7502FTL | Multiple |  | Purchase | SMT | 1 | PCS | R7E14 |
| 3 | B55.00X01.S033 | 64.75R05.6DL | CHIP RES 75 F 1/16W 0402 | R2_SA;HF_SA;G_SA; | Released | TA-I;RALEC;CYNTEC;YAGEO;WALSIN | RM04FTN75R0 ; RTT0275R0FTH ; RR0510S-750-FN ; RC0402FR-0775RL;WR04X75R0FTL | Multiple |  | Purchase | SMT | 5 | PCS | R2T16 R2T31 R2T43 R3P41 R7E2 |
| 3 | B55.00X01.S033 | 64.78715.6DL | CHIP RES 7.87K F 1/16W 0402 | R2_SA;HF_SA;G_SA; | Released | TA-I;RALEC;CYNTEC;YAGEO | RM04FTN7871;RTT027871FTH;RR0510S-7871-FN;RC0402FR-077K87L | Multiple |  | Purchase | SMT | 4 | PCS | R4B8 R4G13 R7B16 R7F18 |
| 3 | B55.00X01.S033 | 64.80615.6DL | CHIP RES 8.06K F 1/16W 0402 | R2_SA;HF_SA;G_SA; | Released | TA-I;RALEC;CYNTEC;YAGEO;WALSIN | RM04FTN8061;RTT028061FTH;RR0510S-8061-FN;RC0402FR-078K06L;WR04X8061FTL | Multiple |  | Purchase | SMT | 1 | PCS | R4C12 |
| 3 | B55.00X01.S033 | 64.82015.6DL | CHIP RES 8.2K F 1/16W 0402 | R2_SA;HF_SA;G_SA; | Released | TAI;RALEC;CYNTEC;YAGEO | RM04FTN8201;RTT028201FTH;RR0510S-822-FN;RC0402FR-078K2L | Multiple |  | Purchase | SMT | 2 | PCS | R1T25 R1T26 |
| 3 | B55.00X01.S033 | 64.82025.6DL | CHIP RES 82K F 1/16W 0402 | R2_SA;HF_SA;G_SA; | Released | TA-I;RALEC;CYNTEC;YAGEO | RM04FTN8202;RTT028202FTH;RR0510S-823-FN;RC0402FR-0782KL | Multiple |  | Purchase | SMT | 1 | PCS | RN8F6 |
| 3 | B55.00X01.S033 | 64.88705.6DL | CHIP RES 887 F 1/16W 0402 | R2_SA;HF_SA;G_SA; | Released | TA-I ; RALEC ; CYNTEC ; YAGEO | RM04FTN8870 ; RTT028870FTH ; RR0510S-8870-FN ; RC0402FR-07887RL | Multiple |  | Purchase | SMT | 2 | PCS | R2R8 R9B7 |
| 3 | B55.00X01.S033 | 64.90925.6DL | CHIP RES 90.9K F 1/16W 0402 | R2_SA;HF_SA;G_SA; | Released | TA-I;RALEC;CYNTEC;YAGEO;WALSIN | RM04FTN9092;RTT029092FTH;RR0510S-9092-FN;RC0402FR-0790K9L;WR04X9092FTL | Multiple |  | Purchase | SMT | 3 | PCS | R1D13 R3P48 R9P28 |
| 3 | B55.00X01.S033 | 64.90R95.6DL | CHIP RES 90.9 F 1/16W 0402 | R2_SA;HF_SA;G_SA; | Released | TA-I ; RALEC ; CYNTEC ; YAGEO | RM04FTN90R9 ; RTT0290R9FTH ; RR0510S-90R9-FN ; RC0402FR-0790R9L | Multiple |  | Purchase | SMT | 8 | PCS | R3D1 R3D2 R4P10 R4P8 R5D1 R5D2 R7P16 R7P17 |
| 3 | B55.00X01.S033 | 64.R0005.55L | CHIP RES 0 F 1/10W 0603 | R2_SA;HF_SA;G_SA; | Released | RALEC;WALSIN;YAGEO;TAI | RTT030000FTP;WR06X000 PTL;RC0603FR-070RL;RM06FTN0 | Multiple |  | Purchase | SMT | 26 | PCS | R25W120 R25W93 R4B13 R4G24 R7B19 R7F8 RT1 RT11 RT14 RT15 RT17 RT19 RT23 RT25 RT28 RT3 RT30 RT33 RT37 RT40 RT41 RT44 RT46 RT47 RT5 RT9 |
| 3 | B55.00X01.S033 | 68.00040.211 | CHIP BEAD MMZ1608R300A TDK | R2_SA;HF_SA; | Released | TDK | MMZ1608R300A | Single |  | Purchase | SMT | 2 | PCS | FB1U3 FB1U4 |
| 3 | B55.00X01.S033 | 68.00084.831 | CHIP BEAD BLM21PG220SN1D (LF) | R2_SA;HF_SA; | Released | MURATA | BLM21PG220SN1D | Single |  | Purchase | SMT | 5 | PCS | FB4A1 FB4G1 FB7B1 FB7E1 FB7F1 |
| 3 | B55.00X01.S033 | 68.00084.921 | CHIP BAED BLM15AG121SN1D | R2_SA;HF_SA;G_SA; | Released | MURATA | BLM15AG121SN1D | Single |  | Purchase | SMT | 5 | PCS | FB25W1 FB25W2 FB25W3 FB25W4 FB25W5 |
| 3 | B55.00X01.S033 | 68.00084.A31 | CHIP BEAD BLM18PG121SN1D 0603 | R2_SA;HF_SA;G_SA; | Released | MURATA | BLM18PG121SN1D | Single |  | Purchase | SMT | 6 | PCS | FB2M1 FB2M2 FB3M1 FB3M2 FB3M3 FB3M4 |
| 3 | B55.00X01.S033 | 68.00109.171 | CHIP BEAD MMZ2012S601ATA1N TDK | R2_SA;HF_SA; | Released | TDK | MMZ2012S601ATA1N | Single |  | Purchase | SMT | 2 | PCS | FB2T2 FB6P1 |
| 3 | B55.00X01.S033 | 68.00230.231 | CHIP BEAD HCB1608KF-800T30 | R2_SA;HF_SA; | Released | TAITECH | HCB1608KF-800T30 | Single |  | Purchase | SMT | 5 | PCS | FB2T1 FB2T3 FB2T4 FB2T5 FB2T7 |
| 3 | B55.00X01.S033 | 68.6803N.10D | CHIP IND 68NH LQG18HN68NJ00D | R2_SA;HF_SA; | Released | MURATA | LQG18HN68NJ00D | Single |  | Purchase | SMT | 3 | PCS | L25W1 L25W2 L25W3 |
| 3 | B55.00X01.S033 | 69.43001.511 | CHIP FUSE 3A 75V 0458003.DR | R2_SA;HF_SA; | Released | LITTELFUSE | 0458003.DR | Single |  | Purchase | SMT | 1 | PCS | F8B1 |
| 3 | B55.00X01.S033 | 69.50007.D81 | POLYSW 8V/1.1A 1206L110THYR PTC SMD | R2_SA;HF_SA; | Released | LITTELFUSE | 1206L110THYR | Single |  | Purchase | SMT | 1 | PCS | F30W1 |
| 3 | B55.00X01.S033 | 69.50007.H51 | POLYSW 2.6A/16V MINISMDC260F/16 SMD | R2_SA;HF_SA; | Obsoleted | TE | MINISMDC260F/16 | Single |  | Purchase | SMT | 1 | PCS | F9B1 |
| 3 | B55.00X01.S033 | 71.09554.C0W | IC I/O PCA9554PWR TSSOP 16P | R2_SA;HF_SA; | Released | TI | PCA9554PWR | Single |  | Purchase | SMT | 1 | PCS | U6W11 |
| 3 | B55.00X01.S033 | 71.09617.A0W | IC REPEATER PCA9617ADPJ TSSOP 8P | R2_SA;HF_SA; | Released | NXP | PCA9617ADPJ | Single |  | Purchase | SMT | 5 | PCS | U1W3 U3B1 U4G1 U6F1 U7E1 |
| 3 | B55.00X01.S033 | 72.24C64.R01 | IC EEPROM M24C64-WMN6TP SO8 | R2_SA;HF_SA; | Released | ST | M24C64-WMN6TP | Single |  | Purchase | SMT | 2 | PCS | U6W3 U8D4 |
| 3 | B55.00X01.S033 | 73.01G07.EHH | IC CMOS 74LVC1G07DCKR SC70-5 | R2_SA;HF_SA; | Released | TI | SN74LVC1G07DCKR | Single |  | Purchase | SMT | 12 | PCS | U10W1 U1L4 U1R1 U25W14 U25W15 U25W9 U2P1 U8D2 U8D3 U8G2 U8G3 U9A1 |
| 3 | B55.00X01.S033 | 73.01G08.L03 | IC CMOS SN74LVC1G08DCKR SC-70 | R2_SA;HF_SA;G_SA; | Released | TI | SN74LVC1G08DCKR | Single |  | Purchase | SMT | 8 | PCS | U14E2 U14E3 U1E2 U1M1 U25W17 U25W18 U7E2 U7E3 |
| 3 | B55.00X01.S033 | 73.01G86.ABH | IC CMOS 74AHCT1G86DCKR DCK 5P | R2_SA;HF_SA; | Released | TI | SN74AHCT1G86DCKR | Single |  | Purchase | SMT | 1 | PCS | U1L2 |
| 3 | B55.00X01.S033 | 73.02G07.02J | IC CMOS SN74LVC2G07DCKR SC-70 | R2_SA;HF_SA; | Released | TI | SN74LVC2G07DCKR | Single |  | Purchase | SMT | 2 | PCS | U8F3 U8G1 |
| 3 | B55.00X01.S033 | 73.03157.C0H | IC SW NC7SB3157P6X_NL SC-70 6P | R2_SA;HF_SA; | Released | FAIRCHILD | NC7SB3157P6X_NL | Single |  | Purchase | SMT | 5 | PCS | U1M2 U1M7 U2M1 U6W12 U8W2 |
| 3 | B55.00X01.S033 | 73.03357.00B | IC BUS SW FSA3357K8X US8P | R2_SA;HF_SA; | Released | FAIRCHILD | FSA3357K8X | Single |  | Purchase | SMT | 2 | PCS | U9F1 U9F2 |
| 3 | B55.00X01.S033 | 73.07408.0H3 | IC CMOS SN74LVC08ARGYRG4 QFN14 | R2_SA;HF_SA; | Released | TI | SN74LVC08ARGYRG4 | Single |  | Purchase | SMT | 1 | PCS | U8E1 |
| 3 | B55.00X01.S033 | 73.1G125.D0G | IC CMOS U74AHCT1G125G-AL5-R SO | R2_SA;HF_SA; | Released | UTC | U74AHCT1G125G-AL5-R | Single |  | Purchase | SMT | 2 | PCS | U25W7 U25W8 |
| 3 | B55.00X01.S033 | 73.1G125.I0G | IC BUS SN74CBTLV1G125DCKR SC-70 5P | R2_SA;HF_SA; | Released | TI | SN74CBTLV1G125DCKR | Single |  | Purchase | SMT | 4 | PCS | U1M4 U1M6 U7D1 U8W1 |
| 3 | B55.00X01.S033 | 73.1G126.0AB | IC BUS BUF 74HC1G126GW,125 TSSOP5 | R2_SA;HF_SA; | Released | NEXPERIA | 74HC1G126GW,125 | Single |  | Purchase | SMT | 9 | PCS | U1D1 U1R2 U25W19 U6W4 U6W5 U6W6 U8D5 U8E3 U8E4 |
| 3 | B55.00X01.S033 | 73.33257.B0C | IC BUS SW PI3B3257AQE QSOP 16P | R2_SA;HF_SA; | Released | PERICOM | PI3B3257AQE | Single |  | Purchase | SMT | 2 | PCS | U2T1 U8F1 |
| 3 | B55.00X01.S033 | 74.00331.A2F | IC V.R LMV331IDCKRG4 SC-70 5P | R2_SA;HF_SA; | Released | TI | LMV331IDCKRG4 | Single |  | Purchase | SMT | 1 | PCS | Q9W4 |
| 3 | B55.00X01.S033 | 74.01085.03P | IC V.R ADM1085AKSZ-REE7 SC70-6 | R2_SA;HF_SA; | Obsoleted | ANALOG DEVICE | ADM1085AKSZ-REE7 | Single |  | Purchase | SMT | 1 | PCS | U7D3 |
| 3 | B55.00X01.S033 | 74.01278.A7Z | IC SWAP CTRL ADM1278-1ACPZ LFCSP 32P | R2_SA;HF_SA; | Obsoleted | ADI | ADM1278-1ACPZ | Single |  | Purchase | SMT | 1 | PCS | EU1D2 |
| 3 | B55.00X01.S033 | 74.04214.079 | IC TEMP SEN TMP421AIDCNRG4 SOT23 8P | R2_SA;HF_SA; | Released | TI | TMP421AIDCNRG4 | Single |  | Purchase | SMT | 2 | PCS | U1E1 U9B4 |
| 3 | B55.00X01.S033 | 74.54821.073 | IC PWM TPS54821RHLR QFN 14P | R2_SA;HF_SA; | Released | TI | TPS54821RHLR | Single |  | Purchase | SMT | 1 | PCS | EU7E2 |
| 3 | B55.00X01.S033 | 74.55021.AE3 | IC DRIVER SLG55021-200010VTR TDFN 8P | R2_SA;HF_SA; | Obsoleted | SILEGO | SLG55021-200010VTR | Single |  | Purchase | SMT | 4 | PCS | EU2T1 EU7E1 EU8B1 EU9M1 |
| 3 | B55.00X01.S033 | 74.AD809.A7B | IC RESET ADM809SARTZ-REEL7 SOT-23 | R2_SA;HF_SA; | Released | ADI | ADM809SARTZ-REEL7 | Single |  | Purchase | SMT | 2 | PCS | U1L3 U8E2 |
| 3 | B55.00X01.S033 | 74.MV431.031 | IC A.R LMV431AIMFX 1% SOT23-3 | R2_SA;HF_SA; | Released | TI | LMV431AIMFX | Single |  | Purchase | SMT | 1 | PCS | VR32W1 |
| 3 | B55.00X01.S033 | 75.00070.A7D | IC DIODE S.B BAS70-05-7-F SOT-23 3P | R2_SA;HF_SA;G_SA; | Released | DIODES | BAS70-05-7-F | Single |  | Purchase | SMT | 1 | PCS | CR2U1 |
| 3 | B55.00X01.S033 | 75.00138.07C | IC MOSFET BSS138DW-7-F NC SOT363 | R2_SA;HF_SA; | Released | DIODES | BSS138DW-7-F | Single |  | Purchase | SMT | 15 | PCS | Q1L2 Q2U1 Q3U1 Q4B1 Q4B2 Q4U1 Q7E1 Q7E2 Q7E3 Q7E5 Q7E6 Q9A2 Q9E1 Q9F1 Q9G1 |
| 3 | B55.00X01.S033 | 75.01045.073 | IC ESD ARR AZ1045-04F.R7 DFN2510P10E 10P | R2_SA;HF_SA;G_SA; | Released | AMAZING | AZ1045-04F.R7G | Single |  | Purchase | SMT | 4 | PCS | CR1M2 CR25W1 CR25W2 CR30W1 |
| 3 | B55.00X01.S033 | 75.03904.B7C | IC XTOR MMDT3904 DUAL NPN SOT-363 | R2_SA;HF_SA; | Released | DIODES | MMDT3904-7-F | Single |  | Purchase | SMT | 2 | PCS | Q8D1 Q8W1 |
| 3 | B55.00X01.S033 | 77.22271.L03 | CHIP CAP POS 220U 10V M7343 | R2_SA;HF_SA; | Released | PANASONIC | 10TPE220ML | Single |  | Purchase | SMT | 1 | PCS | C8E4 |
| 3 | B55.00X01.S033 | 77.23371.32L | CHIP CAP POS 330U 6.3V M 6TPF330M9L | R2_SA;HF_SA; | Released | SANYO | 6TPF330M9L | Single |  | Purchase | SMT | 4 | PCS | C3B3 C4F7 C6B7 C6F4 |
| 3 | B55.00X01.S033 | 78.10034.1FL | CHIP CAP C 10P 50V J0402 NPO | R2_SA;HF_SA;G_SA; | Released | TAIYO;MURATA;PHYCOMP;DARFON;MURATA;WALSIN;SAMSUNG;YAGEO | UMK105CH100JV-F;GRM1555C1H100JZ01D;223886915109;C1005NP0100JGT;GRM1555C1H100JA01D;0402N100J500CT;CL05C100JB5NNNC;CC0402JRNPO9BN100 | Multiple |  | Purchase | SMT | 3 | PCS | C25W81 C25W82 C9G22 |
| 3 | B55.00X01.S033 | 78.10134.1FL | CHIP CAP C 100P 50V J0402 NPO | R2_SA;HF_SA;G_SA; | Released | AVX;DARFON;MURATA;PHYCOMP;SAMSUNG;TAIYO;WALSIN;YAGEO | CM05CG101J50AH;C1005NP0101JGT;GRM1555C1H101JA01D;223886915101;CL05C101JB5NNNC;UMK105CH101JV-F;0402N101J500CT;CC0402JRNPO9BN101 | Multiple |  | Purchase | SMT | 8 | PCS | C25W16 C25W57 C25W78 C25W79 C4B4 C4G6 C7B10 C7F9 |
| 3 | B55.00X01.S033 | 78.10224.2FL | CHIP CAP C 1000P 50V K0402 X7R | R2_SA;HF_SA;G_SA; | Released | AVX;DARFON;MURATA;PHYCOMP;SAMSUNG;TAIYO;MURATA;AVX;YAGEO | CM05X7R102K50AH;C1005X7R102KGT;GRM155R71H102KA01D;223858715623;CL05B102KB5NNNC;UMK105B7102KV-F;WBM155R71H102KA01D;04025C102KAT2A;CC0402KRX7R9BB102 | Multiple |  | Purchase | SMT | 24 | PCS | C1B4 C1C23 C1G21 C1W16 C3P6 C4A12 C4A3 C4B8 C4D33 C4D42 C4G13 C4G14 C4G9 C7B12 C7B3 C7E10 C7F11 C7F14 C8A11 C8A9 C8F2 C9F10 C9F8 C9W10 |
| 3 | B55.00X01.S033 | 78.10322.2FL | CHIP CAP C 0.01U 25V K0402 X7R | R2_SA;HF_SA;G_SA; | Released | AVX;DARFON;MURATA;PHYCOMP;SAMSUNG;TAIYO;TDK;MURATA;YAGEO | 04023C103KAT2A;C1005X7R103KFT;GRM155R71E103KA01D;223891715636;CL05B103KA5NNNC;TMK105BJ103KV-F;C1005X7R1E103KT000F;WBM155R71E103KA01D;CC0402KRX7R8BB103 | Multiple |  | Purchase | SMT | 92 | PCS | C10W3 C10W5 C1A17 C1A5 C1B15 C1B9 C1F19 C1F22 C1F9 C1G10 C1G18 C1G19 C1G8 C1L20 C1M28 C1M30 C1M31 C1M34 C1M35 C1M36 C25W11 C2L10 C2L12 C2L13 C2L14 C2L15 C2L16 C2L17 C2L18 C2L19 C2L20 C2L21 C2L22 C2L23 C2L24 C2L26 C2L27 C2L3 C2L37 C2L38 C2L39 C2L4 C2L40 C2L41 C2L42 C2L43 C2L44 C2L47 C2L48 C2L49 C2L5 C2L50 C2L51 C2L52 C2L6 C2L7 C2L9 C2P8 C2T18 C2T27 C2T37 C4A18 C4A5 C4B12 C4F10 C4F9 C4G1 C4G17 C4G19 C4G3 C6L1 C6L2 C6L6 C6L7 C6M1 C6M2 C6T1 C6U17 C6U9 C7F1 C8F5 C8W6 C9L1 C9L3 C9L7 C9L8 C9M1 C9M2 C9T7 C9U10 C9U7 CN8F2 |
| 3 | B55.00X01.S033 | 78.10421.L0L | CHIP CAP C 0.1U 16V K0402 X7R 13" REEL | R2_SA;HF_SA;G_SA; | Released | PHYCOMP;DARFON;WALSIN;MURATA;SAMSUNG;TAIYO;TDK;YAGEO | 223878755649;C1005X7R104KEA;0402B104K160CG;GRM155R71C104KA88J;CL05B104KO5NNND;EMK105B7104KV-M;C1005X7R1C104KT009F;CC0402KPX7R7BB104 | Multiple |  | Purchase | SMT | 258 | PCS | C10W2 C10W4 C14W1 C14W2 C1A10 C1A20 C1B19 C1B2 C1B5 C1C14 C1C17 C1C25 C1C8 C1C9 C1D11 C1D13 C1D21 C1D26 C1D27 C1D28 C1D34 C1D9 C1E14 C1E20 C1E22 C1F28 C1G14 C1G22 C1G25 C1L11 C1L16 C1L17 C1L4 C1L8 C1L9 C1M20 C1M22 C1M23 C1M24 C1M29 C1M38 C1R27 C1R28 C1T10 C1T11 C1T56 C1U22 C1W18 C1W19 C25P80 C25P83 C25W100 C25W101 C25W13 C25W14 C25W15 C25W20 C25W21 C25W22 C25W31 C25W34 C25W38 C25W45 C25W49 C25W55 C25W58 C25W61 C25W68 C25W7 C25W8 C25W9 C25W90 C25W93 C25W95 C25W96 C25W97 C25W99 C2L11 C2M3 C2M4 C2P1 C2P11 C2P12 C2P13 C2P14 C2P15 C2P16 C2P2 C2P3 C2P4 C2P5 C2P6 C2P7 C2P9 C2R1 C2R15 C2R16 C2R17 C2R18 C2R2 C2R3 C2R4 C2R5 C2T1 C2T12 C2T15 C2T16 C2T17 C2T2 C2T21 C2T24 C2T25 C2T26 C2T29 C2T3 C2T30 C2T32 C2T34 C2T35 C2T36 C2T4 C2T5 C2T8 C2U19 C2U20 C2U21 C2U22 C2U23 C2U24 C2U25 C2U27 C2U28 C30W1 C30W2 C32W1 C32W2 C32W3 C32W4 C3B4 C3B5 C3F2 C3N29 C3P2 C3P43 C3P44 C3P46 C3P47 C3P48 C3P49 C3P5 C3P51 C3P52 C3P7 C3R1 C3R2 C3R3 C3W2 C4A20 C4C10 C4C19 C4D11 C4D19 C4D20 C4D22 C4D24 C4D26 C4D32 C4D35 C4D38 C4D40 C4D49 C4E13 C4E20 C4G22 C4G25 C6F1 C6F2 C6F3 C6P10 C6P11 C6P12 C6P4 C6P5 C6P6 C6P9 C6U5 C6W1 C6W10 C6W14 C6W2 C6W3 C6W4 C7A20 C7A38 C7A39 C7A40 C7A5 C7B2 C7B6 C7C11 C7D1 C7D5 C7E1 C7E2 C7E3 C7E4 C7E5 C7E9 C7F15 C7F17 C7F6 C7G29 C7G36 C7W1 C8A3 C8A8 C8B5 C8B7 C8B8 C8C12 C8C13 C8C14 C8C15 C8D1 C8D2 C8D4 C8E1 C8E18 C8E19 C8E2 C8E3 C8E5 C8E8 C8F16 C8F17 C8W2 C9A1 C9A2 C9A3 C9A4 C9A5 C9B10 C9B7 C9F23 C9F5 C9M5 C9M6 C9M7 C9M8 C9M9 C9P11 C9P15 C9P6 C9R13 C9R14 C9W5 C9W7 C9W8 |
| 3 | B55.00X01.S033 | 78.10422.2BL | CHIP CAP C 0.1U 25V K0603 X7R | R2_SA;HF_SA;G_SA; | Released | AVX;DARFON;MURATA;PHYCOMP;SAMSUNG;TAIYO;WALSIN;YAGEO | 06033C104KAT2A;C1608X7R104KFT;GRM188R71E104KA01D;223891615649;CL10B104KA8NNNC;TMK107B7104KA-T;0603B104K250CT;CC0603KRX7R8BB104 | Multiple |  | Purchase | SMT | 7 | PCS | C4B15 C4G26 C7B30 C7F4 C8A4 C8E12 C8E6 |
| 3 | B55.00X01.S033 | 78.10521.5BL | CHIP CAP C 1U 16V K0603 X5R | R2_SA;HF_SA;G_SA; | Released | AVX;DARFON;MURATA;PHYCOMP;SAMSUNG;TAIYO;TDK;WALSIN;YAGEO | CM105X5R105K16AT;C1608X5R105KET;GRM188R61C105KA93D;223878613663;CL10A105KO8NNNC;EMK107BJ105KA-T;C1608X5R1C105KT;0603X105K160CT;CC0603KRX5R7BB105 | Multiple |  | Purchase | SMT | 3 | PCS | C25W17 C25W18 C8W1 |
| 3 | B55.00X01.S033 | 78.10523.8FL | CHIP CAP C 1U 10V K 0402 X6S | R2_SA;HF_SA;G_SA; | Released | TAIYO;MURATA;SAMSUNG;DARFON;YAGEO;WALSIN | LMK105C6105KV-F;GRM155C81A105KA12D;CL05X105KP5NNNC;C1005X6S105KDT;CC0402KRX6S6BB105;0402S105K100CT | Multiple |  | Purchase | SMT | 21 | PCS | C1A2 C1C18 C1C3 C1D15 C1D5 C1E23 C1E6 C1G4 C3L1 C3L29 C4C14 C4C4 C4D14 C4D6 C4E25 C4E28 C4E6 C7A18 C7C20 C7G35 C9B9 |
| 3 | B55.00X01.S033 | 78.1061T.8BL | CHIP CAP C 10U 4V M0603 X6S | R2_SA;HF_SA; | Released | DARFON;MURATA;SAMSUNG;TAIYO | C1608X6S106MBT;GRM188C80G106ME47D;CL10X106MR8NNNC;AMK107AC6106MA-T | Multiple |  | Purchase | SMT | 18 | PCS | C25W29 C2M10 C2M5 C2N6 C3D3 C3M17 C3M18 C3M23 C3M24 C4A15 C6D1 C6L3 C6L4 C6L5 C6U13 C6U14 C6U15 C6U16 |
| 3 | B55.00X01.S033 | 78.12034.1FL | CHIP CAP C 12P 50V J0402 NPO | R2_SA;HF_SA;G_SA; | Released | AVX;MURATA;PHYCOMP;TAIYO;TDK;DARFON;MURATA;WALSIN;YAGEO | 04025A120JAT2A;GRM1555C1H120JZ01D;223886915129;UMK105CH120JW-F;C1005C0G1H120J;C1005NP0120JGT;GRM1555C1H120JA01D;0402N120J500CT;CC0402JRNPO9BN120 | Multiple |  | Purchase | SMT | 6 | PCS | C25W72 C25W73 C25W74 C25W75 C25W76 C25W77 |
| 3 | B55.00X01.S033 | 78.15034.1FL | CHIP CAP C 15P 50V J0402 NPO | R2_SA;HF_SA;G_SA; | Released | AVX;DARFON;MURATA;PHYCOMP;SAMSUNG;TAIYO;WALSIN;YAGEO | 04025A150JAT2A;C1005NP0150JGT;GRM1555C1H150JA01D;223886915159;CL05C150JB5NNNC;UMK105CH150JV-F;0402N150J500LT;CC0402JRNPO9BN150 | Multiple |  | Purchase | SMT | 4 | PCS | C7C13 C7C15 C8F18 C8F19 |
| 3 | B55.00X01.S033 | 78.22124.2FL | CHIP CAP C 220P 50V K0402 X7R | R2_SA;HF_SA;G_SA; | Released | MURATA;AVX;TAIYO;PHYCOMP;DARFON;WALSIN;YAGEO | GRM155R71H221KA01D;04025C221KAT2A;UMK105B7221KV-F;223858715614;C1005X7R221KGT;0402B221K500CT;CC0402KRX7R9BB221 | Multiple |  | Purchase | SMT | 24 | PCS | C1B11 C1B12 C1C10 C1C11 C1C16 C1D1 C1G16 C1G24 C2L2 C3N39 C4D17 C4D18 C4D29 C4D44 C4D45 C4W1 C4W2 C4W3 C4W4 C7A28 C7A29 C7G3 C7G4 C8A2 |
| 3 | B55.00X01.S033 | 78.22224.2FL | CHIP CAP C 2200P 50V K0402 X7R | R2_SA;HF_SA;G_SA; | Released | MURATA;AVX;TAIYO;PHYCOMP;DARFON;SAMSUNG;WALSIN;YAGEO | GRM155R71H222KA01D;04025C222KAT2A;UMK105B7222KV-F;223858715627;C1005X7R222KGT;CL05B222KB5NNNC;0402B222K500CT;CC0402KRX7R9BB222 | Multiple |  | Purchase | SMT | 9 | PCS | C4B7 C4B9 C4G10 C4G11 C7B13 C7B14 C7F12 C7F13 C8F1 |
| 3 | B55.00X01.S033 | 78.22321.2FL | CHIP CAP 0.022U 16V K0402 X7R | R2_SA;HF_SA;G_SA; | Released | AVX;MURATA;PHYCOMP;TAIYO;TDK;DARFON;WALSIN;YAGEO | 0402YC223KAT2A;GRM155R71C223KA01D;223878715641;EMK105B7223KV-F;C1005X7R1C223KT;C1005X7R223KET;0402B223K160CT;CC0402KRX7R7BB223 | Multiple |  | Purchase | SMT | 1 | PCS | C8E15 |
| 3 | B55.00X01.S033 | 78.22421.2FL | CHIP CAP C 0.22U 16V K0402 X7R | R2_SA;HF_SA;G_SA; | Released | MURATA;SAMSUNG;DARFON;TAIYO;WALSIN;YAGEO | GRM155R71C224KA12D;CL05B224KO5NNNC;C1005X7R224KET;EMK105B7224KV-FR;0402B224K160CT;CC0402KRX7R7BB224 | Multiple |  | Purchase | SMT | 193 | PCS | C1A18 C1B21 C1C12 C1C24 C1C4 C1D10 C1D16 C1D20 C1D33 C1D36 C1D6 C1E11 C1E25 C1E7 C1F10 C1F11 C1F12 C1F13 C1F14 C1F15 C1F16 C1F17 C1F18 C1F2 C1F20 C1F3 C1F4 C1F5 C1F6 C1F8 C1G11 C1G5 C1M10 C1M11 C1M12 C1M13 C1M14 C1M15 C1M16 C1M17 C1M18 C1M19 C1M6 C1M7 C1M8 C1M9 C1R1 C1R10 C1R2 C1R3 C1R4 C1R5 C1R6 C1R7 C1R8 C1R9 C1W20 C2M14 C2M15 C2R10 C2R13 C2R14 C2R7 C2R8 C2R9 C2T10 C2T11 C2T13 C2T14 C2T20 C2T23 C3M37 C3M40 C3M41 C3M44 C3M45 C3N13 C3N8 C3N9 C3P10 C3P12 C3P14 C3P16 C3P19 C3P21 C3P22 C3P24 C3P26 C3P29 C3P31 C3P33 C3P34 C3P36 C3P38 C3P41 C4C17 C4C5 C4C8 C4D13 C4D28 C4D47 C4D5 C4D50 C4D9 C4E17 C4E18 C4E23 C4E27 C4E5 C7A12 C7A17 C7A41 C7A43 C7A44 C7A8 C7B25 C7B26 C7B27 C7B28 C7B29 C7C1 C7C14 C7C18 C7C2 C7C3 C7G10 C7G11 C7G12 C7G13 C7G14 C7G15 C7G16 C7G17 C7G18 C7G19 C7G20 C7G21 C7G22 C7G23 C7G24 C7G25 C7G26 C7G31 C7G34 C7G5 C7G6 C7G7 C7G8 C7G9 C826 C827 C828 C829 C830 C831 C832 C833 C834 C835 C840 C841 C842 C843 C844 C845 C8F12 C8F7 C8G1 C8G10 C8G2 C8G3 C8G4 C8G5 C8G6 C8G7 C8G8 C8G9 C9N1 C9N10 C9N12 C9N14 C9N15 C9N16 C9N17 C9N18 C9N2 C9N3 C9N4 C9N5 C9N6 C9N7 C9N8 C9N9 |
| 3 | B55.00X01.S033 | 78.22610.81L | CHIP CAP C 22U 6.3V M0805 X6S | R2_SA;HF_SA;G_SA; | Released | MURATA;SAMSUNG;TAIYO;DARFON;YAGEO;WALSIN;SAMSUNG | GRM21BC80J226ME51L;CL21X226MQQNNNE;JDK212AC6226MG-T;C2012X6S226MCP;CC0805MKX6S5BB226;0805S226M6R3CT;CL21X226MQQNNNG | Multiple |  | Purchase | SMT | 24 | PCS | C1A12 C1G17 C2L45 C2T6 C2T7 C2T9 C4A1 C4A13 C4G20 C4G24 C5P7 C5P8 C5P9 C6A1 C6G3 C7A30 C7A42 C8A14 C8P5 C8P6 C8P7 C9F13 C9F4 C9W13 |
| 3 | B55.00X01.S033 | 78.2261T.8BL | CHIP CAP 22U 4V M0603 X6S | R2_SA;HF_SA; | Released | MURATA;SAMSUNG;TAIYO;WALSIN;DARFON;SAMSUNG | GRM188C80G226MEA0D;CL10X226MR8NUNE;AMK107BC6226MA-T;0603S226M4R0CT;C1608X6S226MBT;CL10X226MR8NUNE | Multiple |  | Purchase | SMT | 87 | PCS | C2D18 C2D28 C2D29 C2D39 C2D40 C2M1 C2M12 C2M13 C2M2 C2N10 C3D10 C3D11 C3D12 C3D13 C3D14 C3D17 C3D18 C3D19 C3D20 C3D21 C3D4 C3D5 C3D6 C3D7 C3L22 C3L23 C3L24 C3L25 C3L26 C3L27 C3M6 C3M7 C3N10 C3N11 C3N12 C3N24 C3N27 C3N28 C3N30 C3N31 C3W3 C3W4 C4C11 C5D20 C5D21 C5D22 C5D23 C5D33 C5D34 C5D35 C5D36 C5D37 C5D38 C5D48 C5D49 C5D50 C5D51 C5D52 C5D53 C5W1 C5W2 C6D2 C6D5 C6D8 C6N7 C7A36 C7B15 C7B16 C7B17 C7B18 C7B19 C7B20 C7B21 C7B22 C7B23 C7B24 C7C9 C7D3 C8B1 C8B10 C8B11 C8B13 C8B14 C8B2 C8B3 C8B4 C8B9 |
| 3 | B55.00X01.S033 | 78.22621.82L | CHIP CAP C 22UF 16V K1206 X6S | R2_SA;HF_SA; | Released | MURATA;TAIYO;SAMSUNG | GRM31CC81C226KE15L;EMK316BC6226KL-T;CL31X226KOHN3NE | Multiple |  | Purchase | SMT | 3 | PCS | C2P10 C7E11 C8E10 |
| 3 | B55.00X01.S033 | 78.27124.2FL | CHIP CAP C 270P 50V K0402 X7R | R2_SA;HF_SA;G_SA; | Released | AVX;MURATA;PHYCOMP;DARFON;TDK;TAIYO;SAMSUNG;WALSIN;YAGEO | 04025C271KAT2A;GRM155R71H271KA01D;223858715615;C1005X7R271KGT;C1005X7R1H271KT;UMK105BJ271KV-F;CL05B271KB5NNNC;0402B271K500CT;CC0402KRX7R9BB271 | Multiple |  | Purchase | SMT | 1 | PCS | C8E16 |
| 3 | B55.00X01.S033 | 78.33034.1FL | CHIP CAP 33P 50V J0402 NPO(ROHS | R2_SA;HF_SA;G_SA; | Released | AVX;DARFON;MURATA;PHYCOMP;SAMSUNG;TAIYO;MURATA;WALSIN;YAGEO | 04025A330JAT2A;C1005NP0330JGT;GRM1555C1H330JZ01D;223886915339;CL05C330JB5NNNC;UMK105CH330JV-F;GRM1555C1H330JA01D;0402N330J500CT;CC0402JRNPO9BN330 | Multiple |  | Purchase | SMT | 2 | PCS | C8C1 C8C2 |
| 3 | B55.00X01.S033 | 78.33324.2BL | CHIP CAP 0.033U 50V K0603 X7R | R2_SA;HF_SA;G_SA; | Released | MURATA;AVX;PHYCOMP;DARFON;YAGEO | GRM188R71H333KA61D;06035C333KAT2A;223858615643;C1608X7R333KGT;CC0603KRX7R9BB333 | Multiple |  | Purchase | SMT | 2 | PCS | C1W21 C9P14 |
| 3 | B55.00X01.S033 | 78.47034.1FL | CHIP CAP C 47P 50V J0402 NPO | R2_SA;HF_SA;G_SA; | Released | AVX;DARFON;MURATA;PHYCOMP;TAIYO;WALSIN;MURATA;SAMSUNG;YAGEO | 04025A470JAT2A;C1005NP0470JGT;GRM1555C1H470JZ01D;223886915479;UMK105CG470JV-F;0402N470J500CT;GRM1555C1H470JA01D;CL05C470JB5NNNC;CC0402JRNPO9BN470 | Multiple |  | Purchase | SMT | 11 | PCS | C12W1 C12W2 C12W3 C12W4 C1U21 C9G14 C9G15 C9G17 C9G18 C9G20 C9G21 |
| 3 | B55.00X01.S033 | 78.47322.2FL | CHIP CAP C 0.047U 25V K0402 X7R | R2_SA;HF_SA;G_SA; | Released | MURATA;TDK;DARFON;PHYCOMP;WALSIN | GRM155R71E473KA88D;C1005X7R1E473KT000F;C1005X7R473KFT;223891715645;0402B473K250CT | Multiple |  | Purchase | SMT | 1 | PCS | C3P45 |
| 3 | B55.00X01.S033 | 78.4761T.81L | CHIP CAP C 47U 4V M0805 X6S | R2_SA;HF_SA;G_SA; | Released | MURATA;TAIYO;SAMSUNG;DARFON;WALSIN | GRM21BC80G476ME15L;AMK212BC6476MG-T;CL21X476MRYNNNE;C2012X6S476MBP;0805S476M4R0CT | Multiple |  | Purchase | SMT | 11 | PCS | C2L32 C2M11 C2M17 C7A31 C7A32 C7A33 C7B4 C8A12 C8A13 C8B15 C8B16 |
| 3 | B55.00X01.S033 | 78.6R864.1FL | CHIP CAP 6.8P50V D0402 NPO(ROH | R2_SA;HF_SA;G_SA; | Released | AVX;MURATA;PHYCOMP;TDK;MURATA;DARFON;YAGEO | 04025A6R8DAT2A;GRM1555C1H6R8DZ01D;223886915688;C1005C0G1H6R8DT;GRM1555C1H6R8DA01D;C1005NP0689DGT;CC0402DRNPO9BN6R8 | Multiple |  | Purchase | SMT | 2 | PCS | C7C4 C7C5 |
| 3 | B55.00X01.S033 | 79.22710.20L | CHIP CAP EL 220U 6.3V M7343 ESR15 | R2_SA;HF_SA;G_SA; | Released | PANASONIC | EEFCX0J221YR | Single |  | Purchase | SMT | 4 | PCS | C4F11 C4M1 C4T3 C6L8 |
| 3 | B55.00X01.S033 | 79.47719.2IL | CHIP CAP EL 470U 2V M 7.3*4.3 | R2_SA;HF_SA; | Released | PANASONIC | EEFGX0D471R | Single |  | Purchase | SMT | 8 | PCS | C2L25 C2L46 C3L18 C3L19 C3L20 C3L21 C7A27 C8A15 |
| 3 | B55.00X01.S033 | 82.20004.271 | OSC 24MHZ 15P 25PPM 3.2*2.5 SMD | R2_SA;HF_SA; | Released | TXC | 7X24000014 | Single |  | Purchase | SMT | 1 | PCS | Y9F2 |
| 3 | B55.00X01.S033 | 82.30020.I31 | XTAL 25MHZ 4P 10PPM HCX-3SB SMD | R2_SA;HF_SA; | Released | HOSONIC | E3SB25.0000F12G11 | Single |  | Purchase | SMT | 1 | PCS | Y8F1 |
| 3 | B55.00X01.S033 | 83.00110.F70 | CHIP LED BLUE LTST-S110TBKT-5A | R2_SA;HF_SA; | Released | LITEON | LTST-S110TBKT-5A | Single |  | Purchase | SMT | 1 | PCS | DS9A1 |
| 3 | B55.00X01.S033 | 83.00171.C70 | LED 2*1.25 GRN LTST-C171KGKT | R2_SA;HF_SA; | Released | LITEON | LTST-C171KGKT | Single |  | Purchase | SMT | 3 | PCS | DS9A5 DS9A6 DS9E1 |
| 3 | B55.00X01.S033 | 83.00191.I70 | LED GREEN LTST-C191KGKT SMD | R2_SA;HF_SA;G_SA; | Released | LITEON | LTST-C191KGKT | Single |  | Purchase | SMT | 2 | PCS | DS9A4 DS9A7 |
| 3 | B55.00X01.S033 | 83.00320.A70 | LED 3*1 GRN LTST-S320KGKT SMD | R2_SA;HF_SA; | Released | LITEON | LTST-S320KGKT | Single |  | Purchase | SMT | 1 | PCS | DS9A2 |
| 3 | B55.00X01.S033 | 83.04148.B1H | DIODE SW 1N4148W-7-F SOD-123 | R2_SA;HF_SA;G_SA; | Released | DIODES | 1N4148W-7-F | Single |  | Purchase | SMT | 4 | PCS | CR1L1 CR1L2 CR1L3 CR1L4 |
| 3 | B55.00X01.S033 | 83.1221Y.070 | LED YELLOW 12-21/Y2C-CP1Q2B/2C SMD | R2_SA;HF_SA; | Released | EVERLIGHT | 12-21/Y2C-CP1Q2B/2C | Single |  | Purchase | SMT | 1 | PCS | DS9A3 |
| 3 | B55.00X01.S033 | 83.19213.J70 | LED RED 19-213/R6C-AJ2L1AX/3T | R2_SA;HF_SA;G_SA; | Released | EVERLIGHT | 19-213/R6C-AJ2L1AX/3T | Single |  | Purchase | SMT | 1 | PCS | DS9F1 |
| 3 | B55.00X01.S033 | 83.1R004.G8H | DIODE S.B 1N5819HW-7-F SOD-123 | R2_SA;HF_SA; | Released | DIODES | 1N5819HW-7-F | Single |  | Purchase | SMT | 1 | PCS | CR3U1 |
| 3 | B55.00X01.S033 | 83.R2003.K8F | DIODE S.B BAT54WS-7-F SOD-323 | R2_SA;HF_SA; | Released | DIODES | BAT54WS-7-F | Single |  | Purchase | SMT | 7 | PCS | CR3W1 CR6W1 CR6W2 CR7E1 CR8E1 CR9P2 CR9W1 |
| 3 | B55.00X01.S033 | 83.R3004.A8F | DIODE SDMK0340L-7-F SOD-323 | R2_SA;HF_SA;G_SA; | Released | DIODES | SDMK0340L-7-F | Single |  | Purchase | SMT | 6 | PCS | CR10W1 CR10W3 CR1B2 CR1F1 CR1F3 CR1F4 |
| 3 | B55.00X01.S033 | 83.R5003.H8H | DIODE S.B RB551V30 0.5A 30V SOD-323 | R2_SA;HF_SA;G_SA; | Released | PANJIT | RB551V30 | Single |  | Purchase | SMT | 1 | PCS | D25W8 |
| 3 | B55.00X01.S033 | 84.00925.03N | FET MOS PH0925CL,115 NC LFPAK | R2_SA;HF_SA; | Obsoleted | NXP | PH0925CL,115 | Single |  | Purchase | SMT | 3 | PCS | EU1E1 EU1E3 EU9R1 |
| 3 | B55.00X01.S033 | 84.2N702.031 | FET MOS 2N7002K-7 NC SOT-23 2KV 300MA | R2_SA;HF_SA; | Released | DIODES | 2N7002K-7 | Single |  | Purchase | SMT | 19 | PCS | Q1D2 Q1P2 Q1W1 Q1W5 Q25W5 Q2P1 Q2T2 Q4W2 Q6W1 Q6W4 Q7D1 Q7E4 Q7E8 Q8D2 Q8E1 Q8E2 Q8F2 Q9A3 Q9W1 |
| 3 | B55.00X01.S033 | 84.T3904.H11 | XTOR LMBT3904LT1G NPN SOT-23 | R2_SA;HF_SA;G_SA; | Released | LRC | LMBT3904LT1G | Single |  | Purchase | SMT | 9 | PCS | Q1D3 Q1F1 Q1L3 Q1W6 Q2T1 Q6W2 Q9T1 Q9W2 Q9W3 |
| 3 | B55.00X01.S033 | B48.00X33.001B | PCB 15126-1B TIOGA PASS DVT MB 14L BOARD | R2_C;HF_C; | Released | BOARDTEK |  | Single |  | Purchase | SMT | 1 | PCS |  |
| 3 | B55.00X01.S033 | BCS.00X71.0008 | IC PCH LEWISBURG LBG-1G EY82C621QM1X | R2_C; | Released | INTEL | 953098 EY82C621 QM1X | Single |  | Purchase | SMT | 1 | PCS | U7C1 |
| 2 | B55.00X01.D033 | B60.0050J.0001 | ASSY HSINK_VR_67X7X18.5_PUSHPIN | R2_SA;HF_SA; | Released | CCI | Void | Single | E | Purchase | DIP | 1 | PCS |  |
| 2 | B55.00X01.D033 | B60.00X0U.0001 | ASSY HSINK_LEWISBURG_77X51.6X7 TP-ALEXT | R2_C;HF_C; | Released | CCI | TBD | Single | E | Purchase | DIP | 1 | PCS |  |
| 1 | B81.00X10.0058 | BDP.00X10.S009 | DP TIOGA PASS MB 7-IN-1 800X590X245 - 1A | N/A; | Released |  |  | Multiple | E | Manufacture |  | 1 | PCS |  |
| A | B81.00X10.0058 | BDP.00X10.S010 | DP TP HAND CARRY MB 5-IN-1 645X395X240 | N/A; | Released |  |  |  | E | Manufacture |  |  |  |  |
| 2 | BDP.00X10.S009 | 38.09031.001 | DESICCANT CLAY 10G | R2_SA;HF_SA;G_SA; | Released | TBD |  | Single |  | Purchase |  | 1 | PCS |  |
| 2 | BDP.00X10.S009 | 40.54T01.001 | LBL CAUTION FOR P97AE | R2_SA;HF_SA;G_SA; | Released | CHENGMAY | 40.54T01.001 | Single |  | Purchase |  | 1 | PCS |  |
| 2 | BDP.00X10.S009 | 42.5N212.001 | BAG ESD PE 1200*320*0.08MM | R2_SA; | Released | TBD |  | Single |  | Purchase |  | 1 | PCS |  |
| 2 | BDP.00X10.S009 | 42.60X01.001 | BAG ZIP 320*230MM | R2_SA;HF_SA; | Released | HONGWANG;WINGFUNG | 42.60X01.001 | Multiple |  | Purchase |  | 0.01786 | PCS |  |
| 2 | BDP.00X10.S009 | 45.00005.312 | LBL CTN ART 124*40 B/W ALL | R2_SA;HF_SA;G_SA; | Released | CHENGMAY | 45.00005.312 | Single |  | Purchase |  | 0.14286 | PCS |  |
| 2 | BDP.00X10.S009 | 45.57T01.001 | LBL IATA BTY L_METAL FOR ALL | R2_SA;HF_SA; | Released | CYMMETRIK | Void | Single |  | Purchase |  | 0.14286 | PCS |  |
| 2 | BDP.00X10.S009 | 46.30S05.001 | CORNER KRAFT 1150*50*50*3 M1KC | R2_SA;HF_SA;G_SA; | Released | MYS | 46.30S05.001 | Single |  | Purchase |  | 0.03571 | PCS |  |
| 2 | BDP.00X10.S009 | 46.30S14.001 | CORNER KRAFT PAPER 950*50*50*3 | R2_SA;HF_SA;G_SA; | Released | MYS;MOONSHINE | 46.30S14.001 | Multiple |  | Purchase |  | 0.07143 | PCS |  |
| 2 | BDP.00X10.S009 | 46.3ZN01.001 | CORNER PAPER 700*50*50*3MM | R2_SA;HF_SA;G_SA; | Released | COPLASCO;MYS | 46.3ZN01.001 | Multiple |  | Purchase |  | 0.03571 | PCS |  |
| 2 | BDP.00X10.S009 | 46.7A301.001 | AIR-BAG ALL 1800MM X 1000MM | R2_SA;HF_SA;G_SA; | Released | TBD |  | Single |  | Purchase |  | 0.0017 | PCS |  |
| 2 | BDP.00X10.S009 | 47.65F16.001 | PALLET PLYWOOD 1200*800*114MM | R2_SA;HF_SA; | Released | JIAMAO | Void | Single |  | Purchase |  | 0.01786 | PCS |  |
| 2 | BDP.00X10.S009 | B44.00X05.0011 | CTN,AB,OD 800*590*245MM,RSC | R2_SA;HF_SA; | Released | TBD |  | Single |  | Purchase |  | 0.14286 | PCS |  |
| 2 | BDP.00X10.S009 | B46.01102.0001 | PAPER SHEET,AB,1190*790*8MM | R2_SA;HF_SA; | Released | TBD |  | Single |  | Purchase |  | 0.01786 | PCS |  |
| 2 | BDP.00X10.S009 | B47.00X03.0001 | CSN ESD EPE_710X195X65_TIOGA_PASS_MB_V2 | R2_SA;HF_SA; | Released | TBD |  | Single |  | Purchase |  | 1 | PCS |  |
| 2 | BDP.00X10.S009 | B47.00X0Q.0001 | PARTITION,AB,781*210MM,H,8 PCS,MB | R2_SA;HF_SA; | Released | TBD |  | Single |  | Purchase |  | 1.14286 | PCS |  |
| 2 | BDP.00X10.S009 | B47.00X0R.0001 | PARTITION,AB,569*210MM,V,2 PCS,MB | R2_SA;HF_SA; | Released | TBD |  | Single |  | Purchase |  | 0.28571 | PCS |  |
| Level | Parent Number | Part Number | Description | Green Factor | Life Cycle State | Manufacturer | Manufacturer Part Number | Source | BOM Usage | M/P Code | S/D | Qty | UoM | Location |
